G04 ================== begin FILE IDENTIFICATION RECORD ==================*
G04 Layout Name:  9048_F0T_Management_Board_D_brd_V04_1213_1625.brd*
G04 Film Name:    panel*
G04 File Format:  Gerber RS274X*
G04 File Origin:  Cadence Allegro 17.2-S081*
G04 Origin Date:  Tue Dec 13 16:31:11 2022*
G04 *
G04 Layer:  DRAWING FORMAT/TITLE_BLOCK_A*
G04 Layer:  MANUFACTURING/PHOTOPLOT_OUTLINE*
G04 Layer:  DRAWING FORMAT/TITLE_BLOCK*
G04 Layer:  DRAWING FORMAT/TITLE_DATA_PANEL*
G04 Layer:  BOARD GEOMETRY/ASSEMBLY_NOTES*
G04 *
G04 Offset:    (0.00 0.00)*
G04 Mirror:    No*
G04 Mode:      Positive*
G04 Rotation:  0*
G04 FullContactRelief:  No*
G04 UndefLineWidth:     6.00*
G04 ================== end FILE IDENTIFICATION RECORD ====================*
%FSLAX25Y25*MOIN*%
%IR0*IPPOS*OFA0.00000B0.00000*MIA0B0*SFA1.00000B1.00000*%
%ADD10C,.006*%
G75*
%LPD*%
G75*
G36*
G01X-56221Y426772D02*
G02I-1968J0D01*
G37*
G36*
G01X466536Y-450787D02*
G02I-1969J0D01*
G37*
G36*
G01X646982Y-363290D02*
G02I-1969J0D01*
G37*
G54D10*
G01X2010999Y-388000D02*
Y1475775D01*
X-407000D01*
Y-386798D01*
Y-755294D01*
Y-793716D01*
X-368578D01*
X1942346D01*
X2010999D01*
Y-725063D01*
Y-388000D01*
G01X-76641Y470373D02*
X-184897Y473853D01*
G01X-173608Y486297D02*
X-173367Y493793D01*
X-171035Y493718D01*
X-170301Y493319D01*
X-169850Y492805D01*
X-169696Y491799D01*
X-169915Y490806D01*
X-170495Y490199D01*
X-171160Y489845D01*
X-173492Y489920D01*
G01X-171160Y489845D02*
X-169877Y486177D01*
G01X-165818Y492300D02*
X-165234Y493031D01*
X-164569Y493385D01*
X-163819Y493486D01*
X-162894Y493206D01*
X-162261Y492561D01*
X-162099Y491805D01*
X-162216Y491058D01*
X-162609Y490446D01*
X-164515Y489256D01*
X-165383Y488409D01*
X-165983Y487177D01*
X-166205Y486059D01*
X-162287Y485933D01*
G01X-159549Y485845D02*
X-159388Y490842D01*
G01X-159433Y489468D02*
X-159133Y490084D01*
X-158650Y490568D01*
X-157989Y490797D01*
X-157344Y490526D01*
X-156894Y490012D01*
X-156634Y489378D01*
X-156751Y485755D01*
G01X-156634Y489378D02*
X-156334Y489994D01*
X-155852Y490479D01*
X-155191Y490707D01*
X-154546Y490437D01*
X-154095Y489922D01*
X-153839Y489163D01*
X-153952Y485665D01*
G01X-152053Y485604D02*
X-151892Y490601D01*
G01X-151937Y489227D02*
X-151637Y489843D01*
X-151154Y490327D01*
X-150493Y490556D01*
X-149848Y490285D01*
X-149398Y489771D01*
X-149138Y489137D01*
X-149255Y485514D01*
G01X-149138Y489137D02*
X-148838Y489753D01*
X-148356Y490238D01*
X-147695Y490466D01*
X-147050Y490196D01*
X-146599Y489681D01*
X-146343Y488922D01*
X-146456Y485424D01*
G01X-92460Y468420D02*
X-76641Y470373D01*
X-92302Y473339D01*
X-92460Y468420D01*
G01X-77874Y-509842D02*
Y-470551D01*
G02X-70000Y-462677I7874J0D01*
G01X-15748D01*
G02X-7874Y-470551I0J-7874D01*
G01Y-509842D01*
G01X-70000Y-517716D02*
G02X-77874Y-509842I0J7874D01*
G01X-15748Y10197D02*
X-70000D01*
G03X-77874Y2323I0J-7874D01*
G01Y-446929D01*
G03X-70000Y-454803I7874J0D01*
G01X-15748D01*
G03X-7874Y-446929I0J7874D01*
G01Y2323D01*
G03X-15748Y10197I-7874J0D01*
G01X-77874Y466142D02*
Y25945D01*
G03X-70000Y18071I7874J0D01*
G01X-15748D01*
G03X-7874Y25945I0J7874D01*
G01Y413016D01*
G01X-77874D02*
Y466142D01*
G02X-70000Y474016I7874J0D01*
G01X-77874Y466142D02*
G02X-70000Y474016I7874J0D01*
G01X-77874Y484016D02*
Y524016D01*
G01X148864Y514016D02*
X-77874D01*
G01X-70874Y515516D02*
X-77874Y514016D01*
X-70874Y512516D01*
Y515516D01*
G01X-46378Y-517716D02*
X-70000D01*
G01X-62559Y-454803D02*
G02Y-462677I0J-3937D01*
G01Y10197D02*
G03Y18071I0J3937D01*
G01X-70000Y474016D02*
X-15748D01*
G01X-53307Y-609436D02*
Y-684436D01*
X446693D01*
Y-609436D01*
X-53307D01*
G01X-41307Y-674436D02*
Y-679436D01*
G01X-42764Y-674436D02*
X-39850D01*
G01X-34940Y-679436D02*
X-37474D01*
Y-674436D01*
X-34940D01*
G01X-35954Y-676853D02*
X-37474D01*
G01X-32374Y-674436D02*
Y-679436D01*
X-29840D01*
G01X-26007Y-679603D02*
X-26134Y-679519D01*
Y-679353D01*
X-26007Y-679269D01*
X-25880Y-679353D01*
Y-679519D01*
X-26007Y-679603D01*
G01Y-677353D02*
X-26134Y-677269D01*
Y-677103D01*
X-26007Y-677019D01*
X-25880Y-677103D01*
Y-677269D01*
X-26007Y-677353D01*
G01X-21224Y-681103D02*
X-21857Y-680269D01*
X-22174Y-679436D01*
Y-676103D01*
X-21857Y-675269D01*
X-21224Y-674436D01*
G01X-15807D02*
X-16314Y-674603D01*
X-16694Y-675019D01*
X-16947Y-675519D01*
X-17137Y-676186D01*
X-17200Y-676936D01*
X-17137Y-677686D01*
X-16947Y-678353D01*
X-16694Y-678853D01*
X-16314Y-679269D01*
X-15807Y-679436D01*
X-15300Y-679269D01*
X-14920Y-678853D01*
X-14667Y-678353D01*
X-14477Y-677686D01*
X-14414Y-676936D01*
X-14477Y-676186D01*
X-14667Y-675519D01*
X-14920Y-675019D01*
X-15300Y-674603D01*
X-15807Y-674436D01*
G01X-12100Y-678436D02*
X-11720Y-679019D01*
X-11214Y-679353D01*
X-10644Y-679436D01*
X-10137Y-679353D01*
X-9630Y-678936D01*
X-9314Y-678436D01*
X-9250Y-677936D01*
X-9377Y-677353D01*
X-9820Y-676936D01*
X-10264Y-676769D01*
X-10834D01*
G01X-10264D02*
X-9884Y-676519D01*
X-9567Y-676103D01*
X-9440Y-675603D01*
X-9567Y-675103D01*
X-9884Y-674686D01*
X-10454Y-674436D01*
X-11024Y-674519D01*
X-11594Y-674853D01*
G01X-5290Y-681103D02*
X-4657Y-680269D01*
X-4340Y-679436D01*
Y-676103D01*
X-4657Y-675269D01*
X-5290Y-674436D01*
G01X-1900Y-678436D02*
X-1520Y-679019D01*
X-1014Y-679353D01*
X-444Y-679436D01*
X63Y-679353D01*
X570Y-678936D01*
X886Y-678436D01*
X950Y-677936D01*
X823Y-677353D01*
X380Y-676936D01*
X-64Y-676769D01*
X-634D01*
G01X-64D02*
X316Y-676519D01*
X633Y-676103D01*
X760Y-675603D01*
X633Y-675103D01*
X316Y-674686D01*
X-254Y-674436D01*
X-824Y-674519D01*
X-1394Y-674853D01*
G01X3390Y-675269D02*
X3770Y-674769D01*
X4213Y-674519D01*
X4720Y-674436D01*
X5353Y-674603D01*
X5796Y-675019D01*
X5923Y-675519D01*
X5860Y-676019D01*
X5606Y-676436D01*
X4340Y-677269D01*
X3770Y-677853D01*
X3390Y-678686D01*
X3263Y-679436D01*
X5923D01*
G01X9566D02*
X9693Y-678353D01*
X9883Y-677436D01*
X10136Y-676603D01*
X10453Y-675686D01*
X10960Y-674436D01*
X8426D01*
G01X13970Y-677769D02*
X15616D01*
G01X18690Y-675269D02*
X19070Y-674769D01*
X19513Y-674519D01*
X20020Y-674436D01*
X20653Y-674603D01*
X21096Y-675019D01*
X21223Y-675519D01*
X21160Y-676019D01*
X20906Y-676436D01*
X19640Y-677269D01*
X19070Y-677853D01*
X18690Y-678686D01*
X18563Y-679436D01*
X21223D01*
G01X23600Y-678436D02*
X23980Y-679019D01*
X24486Y-679353D01*
X25056Y-679436D01*
X25563Y-679353D01*
X26070Y-678936D01*
X26386Y-678436D01*
X26450Y-677936D01*
X26323Y-677353D01*
X25880Y-676936D01*
X25436Y-676769D01*
X24866D01*
G01X25436D02*
X25816Y-676519D01*
X26133Y-676103D01*
X26260Y-675603D01*
X26133Y-675103D01*
X25816Y-674686D01*
X25246Y-674436D01*
X24676Y-674519D01*
X24106Y-674853D01*
G01X30853Y-679436D02*
Y-674436D01*
X28510Y-678019D01*
X31676D01*
G01X33800Y-678686D02*
X34180Y-679103D01*
X34623Y-679353D01*
X35193Y-679436D01*
X35763Y-679269D01*
X36206Y-678936D01*
X36523Y-678353D01*
X36586Y-677686D01*
X36460Y-677019D01*
X36143Y-676603D01*
X35700Y-676269D01*
X35256Y-676186D01*
X34813Y-676269D01*
X34243Y-676603D01*
X34433Y-674436D01*
X36143D01*
G01X44190Y-679436D02*
Y-674436D01*
X46596D01*
G01X45710Y-676853D02*
X44190D01*
G01X48910Y-679436D02*
X50493Y-674436D01*
X52076Y-679436D01*
G01X51506Y-677686D02*
X49480D01*
G01X54263Y-679436D02*
X56923Y-674436D01*
G01X54263D02*
X56923Y-679436D01*
G01X60693Y-679603D02*
X60566Y-679519D01*
Y-679353D01*
X60693Y-679269D01*
X60820Y-679353D01*
Y-679519D01*
X60693Y-679603D01*
G01Y-677353D02*
X60566Y-677269D01*
Y-677103D01*
X60693Y-677019D01*
X60820Y-677103D01*
Y-677269D01*
X60693Y-677353D01*
G01X65476Y-681103D02*
X64843Y-680269D01*
X64526Y-679436D01*
Y-676103D01*
X64843Y-675269D01*
X65476Y-674436D01*
G01X70893D02*
X70386Y-674603D01*
X70006Y-675019D01*
X69753Y-675519D01*
X69563Y-676186D01*
X69500Y-676936D01*
X69563Y-677686D01*
X69753Y-678353D01*
X70006Y-678853D01*
X70386Y-679269D01*
X70893Y-679436D01*
X71400Y-679269D01*
X71780Y-678853D01*
X72033Y-678353D01*
X72223Y-677686D01*
X72286Y-676936D01*
X72223Y-676186D01*
X72033Y-675519D01*
X71780Y-675019D01*
X71400Y-674603D01*
X70893Y-674436D01*
G01X74600Y-678436D02*
X74980Y-679019D01*
X75486Y-679353D01*
X76056Y-679436D01*
X76563Y-679353D01*
X77070Y-678936D01*
X77386Y-678436D01*
X77450Y-677936D01*
X77323Y-677353D01*
X76880Y-676936D01*
X76436Y-676769D01*
X75866D01*
G01X76436D02*
X76816Y-676519D01*
X77133Y-676103D01*
X77260Y-675603D01*
X77133Y-675103D01*
X76816Y-674686D01*
X76246Y-674436D01*
X75676Y-674519D01*
X75106Y-674853D01*
G01X81410Y-681103D02*
X82043Y-680269D01*
X82360Y-679436D01*
Y-676103D01*
X82043Y-675269D01*
X81410Y-674436D01*
G01X84800Y-678436D02*
X85180Y-679019D01*
X85686Y-679353D01*
X86256Y-679436D01*
X86763Y-679353D01*
X87270Y-678936D01*
X87586Y-678436D01*
X87650Y-677936D01*
X87523Y-677353D01*
X87080Y-676936D01*
X86636Y-676769D01*
X86066D01*
G01X86636D02*
X87016Y-676519D01*
X87333Y-676103D01*
X87460Y-675603D01*
X87333Y-675103D01*
X87016Y-674686D01*
X86446Y-674436D01*
X85876Y-674519D01*
X85306Y-674853D01*
G01X90216Y-678853D02*
X90660Y-679269D01*
X91166Y-679436D01*
X91673Y-679269D01*
X92116Y-678769D01*
X92433Y-678019D01*
X92560Y-677269D01*
Y-676353D01*
X92433Y-675603D01*
X92116Y-674936D01*
X91736Y-674603D01*
X91293Y-674436D01*
X90786Y-674603D01*
X90406Y-674936D01*
X90153Y-675436D01*
X90026Y-676103D01*
X90153Y-676686D01*
X90470Y-677269D01*
X90850Y-677603D01*
X91293Y-677686D01*
X91800Y-677519D01*
X92180Y-677103D01*
X92560Y-676353D01*
G01X96266Y-679436D02*
X96393Y-678353D01*
X96583Y-677436D01*
X96836Y-676603D01*
X97153Y-675686D01*
X97660Y-674436D01*
X95126D01*
G01X100670Y-677769D02*
X102316D01*
G01X105200Y-678436D02*
X105580Y-679019D01*
X106086Y-679353D01*
X106656Y-679436D01*
X107163Y-679353D01*
X107670Y-678936D01*
X107986Y-678436D01*
X108050Y-677936D01*
X107923Y-677353D01*
X107480Y-676936D01*
X107036Y-676769D01*
X106466D01*
G01X107036D02*
X107416Y-676519D01*
X107733Y-676103D01*
X107860Y-675603D01*
X107733Y-675103D01*
X107416Y-674686D01*
X106846Y-674436D01*
X106276Y-674519D01*
X105706Y-674853D01*
G01X110490Y-677353D02*
X110933Y-676769D01*
X111313Y-676436D01*
X111820Y-676269D01*
X112263Y-676436D01*
X112580Y-676769D01*
X112833Y-677269D01*
X112896Y-677853D01*
X112833Y-678353D01*
X112580Y-678853D01*
X112200Y-679269D01*
X111756Y-679436D01*
X111250Y-679269D01*
X110806Y-678769D01*
X110553Y-678019D01*
X110490Y-677186D01*
X110616Y-676103D01*
X110806Y-675519D01*
X111123Y-674936D01*
X111566Y-674519D01*
X112010Y-674436D01*
X112453Y-674603D01*
X112770Y-675019D01*
G01X116793Y-679436D02*
Y-674436D01*
X116033Y-675436D01*
G01Y-679436D02*
X117553D01*
G01X122653D02*
Y-674436D01*
X120310Y-678019D01*
X123476D01*
G01X-15748Y-517716D02*
X-46378D01*
G01X-53110Y-461496D02*
G03I-1575J0D01*
G01X-45236D02*
G03I-1575J0D01*
G01Y16890D02*
G03I-1575J0D01*
G01X-53110D02*
G03I-1575J0D01*
G01X-29488Y-461496D02*
G03I-1575J0D01*
G01X-37362D02*
G03I-1575J0D01*
G01X-23189Y-454803D02*
G03Y-462677I0J-3937D01*
G01Y10197D02*
G02Y18071I0J3937D01*
G01X-37362Y16890D02*
G03I-1575J0D01*
G01X-29488D02*
G03I-1575J0D01*
G01X-7874Y-509842D02*
G02X-15748Y-517716I-7874J0D01*
G01Y474016D02*
G02X-7874Y466142I0J-7874D01*
G01X346457Y-493700D02*
G03X354331Y-485826I0J7874D01*
G01Y-379330D01*
G03X353347Y-378346I-984J0D01*
G01X345473D01*
G02X343504Y-376377I0J1969D01*
G01Y-366535D01*
G02X345473Y-364566I1969J0D01*
G01X353347D01*
G03X354331Y-363582I0J984D01*
G01Y-51574D01*
G03X346457Y-43700I-7874J0D01*
G01X287361D01*
X220511D01*
X7874D01*
G03X0Y-51574I0J-7874D01*
G01Y-363582D01*
G03X985Y-364566I985J1D01*
G01X8859D01*
G02X10827Y-366535I-1J-1968D01*
G01Y-376377D01*
G02X8859Y-378346I-1969J-1D01*
G01X985D01*
G03X0Y-379330I0J-984D01*
G01Y-485826D01*
G03X7874Y-493700I7874J0D01*
G01X17717D01*
G02X19685Y-495669I-1J-1968D01*
G01Y-512724D01*
X22567Y-517716D01*
X39410D01*
X42362Y-514763D01*
Y-495669D01*
G02X44331Y-493700I1969J0D01*
G01X50237D01*
G02X52205Y-495669I0J-1968D01*
G01Y-514763D01*
X55158Y-517716D01*
X88445D01*
X91398Y-514763D01*
Y-494586D01*
G02X100256I4429J0D01*
G01Y-514763D01*
X103209Y-517716D01*
X169548D01*
X172500Y-514763D01*
Y-493798D01*
G02X179784I3642J0D01*
G01Y-514763D01*
X182737Y-517716D01*
X216044D01*
X218996Y-514763D01*
Y-495570D01*
G02X229823I5413J0D01*
G01Y-514763D01*
X232776Y-517716D01*
X299154D01*
X302107Y-514763D01*
Y-495669D01*
G02X304075Y-493700I1968J0D01*
G01X309981D01*
G02X311949Y-495669I-1J-1968D01*
G01Y-514763D01*
X314902Y-517716D01*
X331764D01*
X334646Y-512724D01*
Y-495669D01*
G02X336614Y-493700I1968J0D01*
G01X346457D01*
G01X-1Y-415984D02*
G03X-7875I-3937J0D01*
G01X-1Y-396298D02*
G02X-7875I-3937J0D01*
G01X-1Y-247984D02*
G03X-7875I-3937J0D01*
G01X-1Y-228298D02*
G02X-7875I-3937J0D01*
G01X-1Y-147984D02*
G03X-7875I-3937J0D01*
G01X-1Y-128298D02*
G02X-7875I-3937J0D01*
G01X7874Y450000D02*
G03X0Y442126I0J-7874D01*
G01Y335630D01*
G03X984Y334646I984J0D01*
G01X8858D01*
G02X10827Y332677I0J-1969D01*
G01Y322835D01*
G02X8858Y320866I-1969J0D01*
G01X984D01*
G03X0Y319882I0J-984D01*
G01Y7874D01*
G03X7874Y0I7874J0D01*
G01X66970D01*
X133820D01*
X346457D01*
G03X354331Y7874I0J7874D01*
G01Y319882D01*
G03X353346Y320866I-984J-1D01*
G01X345472D01*
G02X343504Y322835I0J1968D01*
G01Y332677D01*
G02X345472Y334646I1968J0D01*
G01X353346D01*
G03X354331Y335630I0J984D01*
G01Y442126D01*
G03X346457Y450000I-7874J0D01*
G01X336614D01*
G02X334646Y451969I0J1969D01*
G01Y469024D01*
X331764Y474016D01*
X314921D01*
X311969Y471063D01*
Y451969D01*
G02X310000Y450000I-1969J0D01*
G01X304094D01*
G02X302126Y451969I1J1969D01*
G01Y471063D01*
X299173Y474016D01*
X265886D01*
X262933Y471063D01*
Y450886D01*
G02X254075I-4429J0D01*
G01Y471063D01*
X251122Y474016D01*
X184783D01*
X181831Y471063D01*
Y450098D01*
G02X174547I-3642J0D01*
G01Y471063D01*
X171594Y474016D01*
X138287D01*
X135335Y471063D01*
Y451870D01*
G02X124508I-5413J0D01*
G01Y471063D01*
X121555Y474016D01*
X55177D01*
X52224Y471063D01*
Y451969D01*
G02X50256Y450000I-1969J0D01*
G01X44350D01*
G02X42382Y451969I0J1969D01*
G01Y471063D01*
X39429Y474016D01*
X22567D01*
X19685Y469024D01*
Y451969D01*
G02X17717Y450000I-1969J0D01*
G01X7874D01*
G01X-7874Y102639D02*
G02X0I3937J0D01*
G01X-7874Y122325D02*
G03X0I3937J0D01*
G01X-7874Y202639D02*
G02X0I3937J0D01*
G01X-7874Y222325D02*
G03X0I3937J0D01*
G01X-7874Y362639D02*
G02X0I3937J0D01*
G01X-7874Y382325D02*
G03X0I3937J0D01*
G01X-7874Y466142D02*
Y413016D01*
G01X141693Y-609436D02*
Y-684436D01*
G01Y-659436D02*
X244693D01*
Y-634436D01*
G01X141693D02*
X244693D01*
G01X162889Y495266D02*
X158239D01*
Y507766D01*
X162889D01*
G01X246693Y-609436D02*
Y-684436D01*
G01X244693Y-609436D02*
Y-684436D01*
G01X252200Y-669436D02*
Y-664436D01*
X253466D01*
X253973Y-664686D01*
X254353Y-665019D01*
X254670Y-665519D01*
X254923Y-666103D01*
X254986Y-666936D01*
X254923Y-667769D01*
X254670Y-668353D01*
X254353Y-668853D01*
X253973Y-669186D01*
X253466Y-669436D01*
X252200D01*
G01X257110D02*
X258693Y-664436D01*
X260276Y-669436D01*
G01X259706Y-667686D02*
X257680D01*
G01X263793Y-664436D02*
Y-669436D01*
G01X262336Y-664436D02*
X265250D01*
G01X270160Y-669436D02*
X267626D01*
Y-664436D01*
X270160D01*
G01X269146Y-666853D02*
X267626D01*
G01X273993Y-669603D02*
X273866Y-669519D01*
Y-669353D01*
X273993Y-669269D01*
X274120Y-669353D01*
Y-669519D01*
X273993Y-669603D01*
G01Y-667353D02*
X273866Y-667269D01*
Y-667103D01*
X273993Y-667019D01*
X274120Y-667103D01*
Y-667269D01*
X273993Y-667353D01*
G01X246693Y-659436D02*
X446693D01*
G01X252326Y-644436D02*
Y-639436D01*
X253846D01*
X254353Y-639686D01*
X254733Y-640269D01*
X254860Y-640936D01*
X254733Y-641603D01*
X254416Y-642103D01*
X253846Y-642353D01*
X252326D01*
G01X257553Y-644603D02*
X259833Y-639436D01*
G01X262336Y-644436D02*
Y-639436D01*
X265250Y-644436D01*
Y-639436D01*
G01X268893Y-644603D02*
X268766Y-644519D01*
Y-644353D01*
X268893Y-644269D01*
X269020Y-644353D01*
Y-644519D01*
X268893Y-644603D01*
G01Y-642353D02*
X268766Y-642269D01*
Y-642103D01*
X268893Y-642019D01*
X269020Y-642103D01*
Y-642269D01*
X268893Y-642353D01*
G01X246693Y-634436D02*
X446693D01*
G01X252326Y-619436D02*
Y-614436D01*
X253846D01*
X254353Y-614686D01*
X254733Y-615269D01*
X254860Y-615936D01*
X254733Y-616603D01*
X254416Y-617103D01*
X253846Y-617353D01*
X252326D01*
G01X257426Y-619436D02*
Y-614436D01*
X259010D01*
X259516Y-614686D01*
X259833Y-615019D01*
X259960Y-615686D01*
X259833Y-616353D01*
X259453Y-616769D01*
X259010Y-617019D01*
X257426D01*
G01X259010D02*
X259960Y-619436D01*
G01X263793D02*
X263286Y-619353D01*
X262843Y-619019D01*
X262463Y-618519D01*
X262210Y-617936D01*
X262083Y-617269D01*
Y-616603D01*
X262210Y-615936D01*
X262463Y-615353D01*
X262843Y-614853D01*
X263286Y-614519D01*
X263793Y-614436D01*
X264300Y-614519D01*
X264743Y-614853D01*
X265123Y-615353D01*
X265376Y-615936D01*
X265503Y-616603D01*
Y-617269D01*
X265376Y-617936D01*
X265123Y-618519D01*
X264743Y-619019D01*
X264300Y-619353D01*
X263793Y-619436D01*
G01X267626Y-618436D02*
X267943Y-618936D01*
X268323Y-619269D01*
X268766Y-619436D01*
X269273Y-619269D01*
X269653Y-618936D01*
X270033Y-618436D01*
X270160Y-617769D01*
Y-614436D01*
G01X275260Y-619436D02*
X272726D01*
Y-614436D01*
X275260D01*
G01X274246Y-616853D02*
X272726D01*
G01X280486Y-614853D02*
X280106Y-614603D01*
X279663Y-614436D01*
X279156D01*
X278586Y-614686D01*
X278143Y-615103D01*
X277826Y-615603D01*
X277573Y-616436D01*
X277510Y-617186D01*
X277636Y-617936D01*
X277826Y-618436D01*
X278206Y-618936D01*
X278650Y-619269D01*
X279093Y-619436D01*
X279536D01*
X279980Y-619269D01*
X280360Y-619019D01*
X280676Y-618686D01*
G01X284193Y-614436D02*
Y-619436D01*
G01X282736Y-614436D02*
X285650D01*
G01X289293Y-619603D02*
X289166Y-619519D01*
Y-619353D01*
X289293Y-619269D01*
X289420Y-619353D01*
Y-619519D01*
X289293Y-619603D01*
G01Y-617353D02*
X289166Y-617269D01*
Y-617103D01*
X289293Y-617019D01*
X289420Y-617103D01*
Y-617269D01*
X289293Y-617353D01*
G01X243489Y495266D02*
X248139D01*
Y507766D01*
X243489D01*
G01X257514Y514016D02*
X484252D01*
G01X362205Y-437984D02*
G03X354331I-3937J0D01*
G01X362205Y-418298D02*
G02X354331I-3937J0D01*
G01X362205Y-247984D02*
G03X354331I-3937J0D01*
G01X362205Y-228298D02*
G02X354331I-3937J0D01*
G01X362205Y-97984D02*
G03X354331I-3937J0D01*
G01X362205Y-78298D02*
G02X354331I-3937J0D01*
G01X354332Y102639D02*
G02X362206I3937J0D01*
G01X354332Y122325D02*
G03X362206I3937J0D01*
G01X354332Y202639D02*
G02X362206I3937J0D01*
G01X354332Y222325D02*
G03X362206I3937J0D01*
G01X354332Y362639D02*
G02X362206I3937J0D01*
G01X354332Y382325D02*
G03X362206I3937J0D01*
G01X361693Y-659436D02*
Y-684436D01*
G01X364326Y-661936D02*
Y-666936D01*
X366860D01*
G01X369933Y-661936D02*
X371453D01*
G01X370693D02*
Y-666936D01*
G01X369933D02*
X371453D01*
G01X376300Y-664269D02*
X376553Y-664019D01*
X376743Y-663603D01*
X376870Y-663019D01*
X376743Y-662519D01*
X376490Y-662186D01*
X376046Y-661936D01*
X374336D01*
Y-666936D01*
X376426D01*
X376870Y-666603D01*
X377123Y-666103D01*
X377250Y-665519D01*
X377123Y-664936D01*
X376743Y-664436D01*
X376300Y-664269D01*
X374336D01*
G01X380893Y-667103D02*
X380766Y-667019D01*
Y-666853D01*
X380893Y-666769D01*
X381020Y-666853D01*
Y-667019D01*
X380893Y-667103D01*
G01Y-664853D02*
X380766Y-664769D01*
Y-664603D01*
X380893Y-664519D01*
X381020Y-664603D01*
Y-664769D01*
X380893Y-664853D01*
G01X370079Y-517716D02*
X452756D01*
G01X370079D02*
G02X362205Y-509842I0J7874D01*
G01D02*
Y-438716D01*
G01D02*
Y425016D01*
G01Y466142D02*
Y423016D01*
G01X370079Y474016D02*
X476378D01*
G01X370079D02*
G03X362205Y466142I0J-7874D01*
G01X404693Y-659436D02*
Y-684436D01*
G01Y-634436D02*
Y-659436D01*
G01X412706Y-687603D02*
X412813Y-687478D01*
X412893Y-687269D01*
X412946Y-686978D01*
X412893Y-686728D01*
X412786Y-686561D01*
X412600Y-686436D01*
X411880D01*
Y-688936D01*
X412760D01*
X412946Y-688769D01*
X413053Y-688519D01*
X413106Y-688228D01*
X413053Y-687936D01*
X412893Y-687686D01*
X412706Y-687603D01*
X411880D01*
G01X415173Y-688936D02*
Y-687269D01*
G01Y-687561D02*
X415066Y-687394D01*
X414906Y-687311D01*
X414720Y-687269D01*
X414533Y-687353D01*
X414373Y-687519D01*
X414266Y-687769D01*
X414213Y-688103D01*
X414266Y-688436D01*
X414373Y-688686D01*
X414533Y-688853D01*
X414720Y-688936D01*
X414906Y-688894D01*
X415066Y-688769D01*
X415173Y-688603D01*
G01X416493Y-688644D02*
X416626Y-688811D01*
X416813Y-688936D01*
X416973D01*
X417133Y-688853D01*
X417240Y-688728D01*
X417293Y-688561D01*
X417266Y-688311D01*
X417160Y-688186D01*
X416680Y-687936D01*
X416573Y-687644D01*
X416626Y-687436D01*
X416733Y-687311D01*
X416893Y-687269D01*
X417053Y-687311D01*
X417213Y-687436D01*
G01X418693Y-687811D02*
X419546D01*
X419466Y-687519D01*
X419333Y-687353D01*
X419146Y-687269D01*
X418960Y-687311D01*
X418800Y-687436D01*
X418693Y-687728D01*
X418640Y-687978D01*
Y-688228D01*
X418693Y-688478D01*
X418826Y-688728D01*
X418986Y-688894D01*
X419173Y-688936D01*
X419360Y-688853D01*
X419546Y-688603D01*
G01X420813Y-688936D02*
Y-686436D01*
G01Y-687686D02*
X420946Y-687436D01*
X421106Y-687311D01*
X421266Y-687269D01*
X421506Y-687353D01*
X421666Y-687519D01*
X421773Y-687811D01*
Y-688144D01*
X421720Y-688478D01*
X421613Y-688728D01*
X421426Y-688894D01*
X421266Y-688936D01*
X421106Y-688894D01*
X420946Y-688769D01*
X420813Y-688561D01*
G01X423493Y-688936D02*
X423333Y-688894D01*
X423173Y-688728D01*
X423066Y-688436D01*
X423013Y-688103D01*
X423066Y-687769D01*
X423173Y-687478D01*
X423333Y-687311D01*
X423493Y-687269D01*
X423653Y-687311D01*
X423813Y-687478D01*
X423920Y-687769D01*
X423946Y-688103D01*
X423920Y-688436D01*
X423813Y-688728D01*
X423653Y-688894D01*
X423493Y-688936D01*
G01X426173D02*
Y-687269D01*
G01Y-687561D02*
X426066Y-687394D01*
X425906Y-687311D01*
X425720Y-687269D01*
X425533Y-687353D01*
X425373Y-687519D01*
X425266Y-687769D01*
X425213Y-688103D01*
X425266Y-688436D01*
X425373Y-688686D01*
X425533Y-688853D01*
X425720Y-688936D01*
X425906Y-688894D01*
X426066Y-688769D01*
X426173Y-688603D01*
G01X427520Y-688936D02*
Y-687269D01*
G01Y-687603D02*
X427653Y-687436D01*
X427786Y-687311D01*
X427973Y-687269D01*
X428106Y-687311D01*
X428266Y-687436D01*
G01X430573Y-686436D02*
Y-688936D01*
G01Y-688561D02*
X430466Y-688769D01*
X430306Y-688894D01*
X430120Y-688936D01*
X429906Y-688853D01*
X429746Y-688644D01*
X429640Y-688394D01*
X429613Y-688103D01*
X429640Y-687811D01*
X429746Y-687561D01*
X429906Y-687353D01*
X430120Y-687269D01*
X430306Y-687311D01*
X430440Y-687394D01*
X430573Y-687561D01*
G01X433960Y-688936D02*
Y-686436D01*
X434626D01*
X434840Y-686561D01*
X434973Y-686728D01*
X435026Y-687061D01*
X434973Y-687394D01*
X434813Y-687603D01*
X434626Y-687728D01*
X433960D01*
G01X434626D02*
X435026Y-688936D01*
G01X436293Y-687811D02*
X437146D01*
X437066Y-687519D01*
X436933Y-687353D01*
X436746Y-687269D01*
X436560Y-687311D01*
X436400Y-687436D01*
X436293Y-687728D01*
X436240Y-687978D01*
Y-688228D01*
X436293Y-688478D01*
X436426Y-688728D01*
X436586Y-688894D01*
X436773Y-688936D01*
X436960Y-688853D01*
X437146Y-688603D01*
G01X438413Y-687269D02*
X438893Y-688936D01*
X439373Y-687269D01*
G01X441093Y-689019D02*
X441040Y-688978D01*
Y-688894D01*
X441093Y-688853D01*
X441146Y-688894D01*
Y-688978D01*
X441093Y-689019D01*
G01X443613Y-688936D02*
Y-686436D01*
X442626Y-688228D01*
X443960D01*
G01X444826Y-688936D02*
X445493Y-686436D01*
X446160Y-688936D01*
G01X445920Y-688061D02*
X445066D01*
G01X408593Y-661936D02*
Y-666936D01*
G01X407136Y-661936D02*
X410050D01*
G01X413693Y-666936D02*
X413313Y-666853D01*
X412933Y-666519D01*
X412680Y-665936D01*
X412553Y-665269D01*
X412680Y-664603D01*
X412933Y-664019D01*
X413313Y-663686D01*
X413693Y-663603D01*
X414073Y-663686D01*
X414453Y-664019D01*
X414706Y-664603D01*
X414770Y-665269D01*
X414706Y-665936D01*
X414453Y-666519D01*
X414073Y-666853D01*
X413693Y-666936D01*
G01X418793D02*
X418413Y-666853D01*
X418033Y-666519D01*
X417780Y-665936D01*
X417653Y-665269D01*
X417780Y-664603D01*
X418033Y-664019D01*
X418413Y-663686D01*
X418793Y-663603D01*
X419173Y-663686D01*
X419553Y-664019D01*
X419806Y-664603D01*
X419870Y-665269D01*
X419806Y-665936D01*
X419553Y-666519D01*
X419173Y-666853D01*
X418793Y-666936D01*
G01X423893D02*
Y-661936D01*
G01X428993Y-667103D02*
X428866Y-667019D01*
Y-666853D01*
X428993Y-666769D01*
X429120Y-666853D01*
Y-667019D01*
X428993Y-667103D01*
G01Y-664853D02*
X428866Y-664769D01*
Y-664603D01*
X428993Y-664519D01*
X429120Y-664603D01*
Y-664769D01*
X428993Y-664853D01*
G01X407326Y-641936D02*
Y-636936D01*
X408910D01*
X409416Y-637186D01*
X409733Y-637519D01*
X409860Y-638186D01*
X409733Y-638853D01*
X409353Y-639269D01*
X408910Y-639519D01*
X407326D01*
G01X408910D02*
X409860Y-641936D01*
G01X414960D02*
X412426D01*
Y-636936D01*
X414960D01*
G01X413946Y-639353D02*
X412426D01*
G01X417210Y-636936D02*
X418793Y-641936D01*
X420376Y-636936D01*
G01X423893Y-642103D02*
X423766Y-642019D01*
Y-641853D01*
X423893Y-641769D01*
X424020Y-641853D01*
Y-642019D01*
X423893Y-642103D01*
G01Y-639853D02*
X423766Y-639769D01*
Y-639603D01*
X423893Y-639519D01*
X424020Y-639603D01*
Y-639769D01*
X423893Y-639853D01*
G01X437008Y477006D02*
Y513406D01*
G01X476378Y-517716D02*
X452756D01*
G01X476378Y474016D02*
X452756D01*
G01X484252Y-438716D02*
Y-509842D01*
G02X476378Y-517716I-7874J0D01*
G01X484252Y423016D02*
Y466142D01*
G03X476378Y474016I-7874J0D01*
G01X477252Y512516D02*
X484252Y514016D01*
X477252Y515516D01*
Y512516D01*
G01X494252Y-517716D02*
X534252D01*
G01X494095D02*
X533882D01*
G01X484252Y423016D02*
Y-438716D01*
G01X494252Y474016D02*
X534252D01*
G01X494095D02*
X579567D01*
G01X484252Y484016D02*
Y524016D01*
G01Y483859D02*
Y554095D01*
G01X524252Y-73375D02*
Y-517716D01*
G01X522752Y-510716D02*
X524252Y-517716D01*
X525752Y-510716D01*
X522752D01*
G01X524252Y29675D02*
Y474016D01*
G01X525752Y467016D02*
X524252Y474016D01*
X522752Y467016D01*
X525752D01*
G01X543002Y-55800D02*
Y-60450D01*
X530502D01*
Y-55800D01*
G01X543002Y12400D02*
Y17050D01*
X530502D01*
Y12400D01*
G01X617735Y-401961D02*
X617988Y-401711D01*
X618178Y-401295D01*
X618305Y-400711D01*
X618178Y-400211D01*
X617925Y-399878D01*
X617481Y-399628D01*
X615771D01*
Y-404628D01*
X617861D01*
X618305Y-404295D01*
X618558Y-403795D01*
X618685Y-403211D01*
X618558Y-402628D01*
X618178Y-402128D01*
X617735Y-401961D01*
X615771D01*
G01X621441Y-404628D02*
Y-401295D01*
G01Y-401961D02*
X621758Y-401628D01*
X622075Y-401378D01*
X622518Y-401295D01*
X622835Y-401378D01*
X623215Y-401628D01*
G01X626478Y-402378D02*
X628505D01*
X628315Y-401795D01*
X627998Y-401461D01*
X627555Y-401295D01*
X627111Y-401378D01*
X626731Y-401628D01*
X626478Y-402211D01*
X626351Y-402711D01*
Y-403211D01*
X626478Y-403711D01*
X626795Y-404211D01*
X627175Y-404545D01*
X627618Y-404628D01*
X628061Y-404461D01*
X628505Y-403961D01*
G01X633668Y-404628D02*
Y-401295D01*
G01Y-401878D02*
X633415Y-401545D01*
X633035Y-401378D01*
X632591Y-401295D01*
X632148Y-401461D01*
X631768Y-401795D01*
X631515Y-402295D01*
X631388Y-402961D01*
X631515Y-403628D01*
X631768Y-404128D01*
X632148Y-404461D01*
X632591Y-404628D01*
X633035Y-404545D01*
X633415Y-404295D01*
X633668Y-403961D01*
G01X636551Y-404628D02*
Y-399628D01*
G01X638578Y-401295D02*
X636551Y-403211D01*
G01X637375Y-402461D02*
X638705Y-404628D01*
G01X642728Y-399628D02*
Y-404628D01*
G01X641841Y-401295D02*
X643615D01*
G01X648968Y-404628D02*
Y-401295D01*
G01Y-401878D02*
X648715Y-401545D01*
X648335Y-401378D01*
X647891Y-401295D01*
X647448Y-401461D01*
X647068Y-401795D01*
X646815Y-402295D01*
X646688Y-402961D01*
X646815Y-403628D01*
X647068Y-404128D01*
X647448Y-404461D01*
X647891Y-404628D01*
X648335Y-404545D01*
X648715Y-404295D01*
X648968Y-403961D01*
G01X651788Y-404628D02*
Y-399628D01*
G01Y-402128D02*
X652105Y-401628D01*
X652485Y-401378D01*
X652865Y-401295D01*
X653435Y-401461D01*
X653815Y-401795D01*
X654068Y-402378D01*
Y-403045D01*
X653941Y-403711D01*
X653688Y-404211D01*
X653245Y-404545D01*
X652865Y-404628D01*
X652485Y-404545D01*
X652105Y-404295D01*
X651788Y-403878D01*
G01X658028Y-404795D02*
X657901Y-404711D01*
Y-404545D01*
X658028Y-404461D01*
X658155Y-404545D01*
Y-404711D01*
X658028Y-404795D01*
G01Y-402545D02*
X657901Y-402461D01*
Y-402295D01*
X658028Y-402211D01*
X658155Y-402295D01*
Y-402461D01*
X658028Y-402545D01*
G01X692525Y-338098D02*
Y-333098D01*
X694931D01*
G01X694045Y-335515D02*
X692525D01*
G01X698828Y-338098D02*
X698448Y-338015D01*
X698068Y-337681D01*
X697815Y-337098D01*
X697688Y-336431D01*
X697815Y-335765D01*
X698068Y-335181D01*
X698448Y-334848D01*
X698828Y-334765D01*
X699208Y-334848D01*
X699588Y-335181D01*
X699841Y-335765D01*
X699905Y-336431D01*
X699841Y-337098D01*
X699588Y-337681D01*
X699208Y-338015D01*
X698828Y-338098D01*
G01X703041D02*
Y-334765D01*
G01Y-335431D02*
X703358Y-335098D01*
X703675Y-334848D01*
X704118Y-334765D01*
X704435Y-334848D01*
X704815Y-335098D01*
G01X712861Y-338098D02*
Y-333098D01*
X714381D01*
X714888Y-333348D01*
X715268Y-333931D01*
X715395Y-334598D01*
X715268Y-335265D01*
X714951Y-335765D01*
X714381Y-336015D01*
X712861D01*
G01X720368Y-338098D02*
Y-334765D01*
G01Y-335348D02*
X720115Y-335015D01*
X719735Y-334848D01*
X719291Y-334765D01*
X718848Y-334931D01*
X718468Y-335265D01*
X718215Y-335765D01*
X718088Y-336431D01*
X718215Y-337098D01*
X718468Y-337598D01*
X718848Y-337931D01*
X719291Y-338098D01*
X719735Y-338015D01*
X720115Y-337765D01*
X720368Y-337431D01*
G01X723251Y-338098D02*
Y-334765D01*
G01Y-335598D02*
X723505Y-335181D01*
X723885Y-334848D01*
X724391Y-334765D01*
X724835Y-334848D01*
X725215Y-335181D01*
X725405Y-335765D01*
Y-338098D01*
G01X728478Y-335848D02*
X730505D01*
X730315Y-335265D01*
X729998Y-334931D01*
X729555Y-334765D01*
X729111Y-334848D01*
X728731Y-335098D01*
X728478Y-335681D01*
X728351Y-336181D01*
Y-336681D01*
X728478Y-337181D01*
X728795Y-337681D01*
X729175Y-338015D01*
X729618Y-338098D01*
X730061Y-337931D01*
X730505Y-337431D01*
G01X734528Y-338098D02*
Y-333098D01*
G01X745235Y-335431D02*
X745488Y-335181D01*
X745678Y-334765D01*
X745805Y-334181D01*
X745678Y-333681D01*
X745425Y-333348D01*
X744981Y-333098D01*
X743271D01*
Y-338098D01*
X745361D01*
X745805Y-337765D01*
X746058Y-337265D01*
X746185Y-336681D01*
X746058Y-336098D01*
X745678Y-335598D01*
X745235Y-335431D01*
X743271D01*
G01X749828Y-338098D02*
X749448Y-338015D01*
X749068Y-337681D01*
X748815Y-337098D01*
X748688Y-336431D01*
X748815Y-335765D01*
X749068Y-335181D01*
X749448Y-334848D01*
X749828Y-334765D01*
X750208Y-334848D01*
X750588Y-335181D01*
X750841Y-335765D01*
X750905Y-336431D01*
X750841Y-337098D01*
X750588Y-337681D01*
X750208Y-338015D01*
X749828Y-338098D01*
G01X756068D02*
Y-334765D01*
G01Y-335348D02*
X755815Y-335015D01*
X755435Y-334848D01*
X754991Y-334765D01*
X754548Y-334931D01*
X754168Y-335265D01*
X753915Y-335765D01*
X753788Y-336431D01*
X753915Y-337098D01*
X754168Y-337598D01*
X754548Y-337931D01*
X754991Y-338098D01*
X755435Y-338015D01*
X755815Y-337765D01*
X756068Y-337431D01*
G01X759141Y-338098D02*
Y-334765D01*
G01Y-335431D02*
X759458Y-335098D01*
X759775Y-334848D01*
X760218Y-334765D01*
X760535Y-334848D01*
X760915Y-335098D01*
G01X766268Y-333098D02*
Y-338098D01*
G01Y-337348D02*
X766015Y-337765D01*
X765635Y-338015D01*
X765191Y-338098D01*
X764685Y-337931D01*
X764305Y-337515D01*
X764051Y-337015D01*
X763988Y-336431D01*
X764051Y-335848D01*
X764305Y-335348D01*
X764685Y-334931D01*
X765191Y-334765D01*
X765635Y-334848D01*
X765951Y-335015D01*
X766268Y-335348D01*
G01X692525Y-338098D02*
Y-333098D01*
X694931D01*
G01X694045Y-335515D02*
X692525D01*
G01X698828Y-338098D02*
X698448Y-338015D01*
X698068Y-337681D01*
X697815Y-337098D01*
X697688Y-336431D01*
X697815Y-335765D01*
X698068Y-335181D01*
X698448Y-334848D01*
X698828Y-334765D01*
X699208Y-334848D01*
X699588Y-335181D01*
X699841Y-335765D01*
X699905Y-336431D01*
X699841Y-337098D01*
X699588Y-337681D01*
X699208Y-338015D01*
X698828Y-338098D01*
G01X703041D02*
Y-334765D01*
G01Y-335431D02*
X703358Y-335098D01*
X703675Y-334848D01*
X704118Y-334765D01*
X704435Y-334848D01*
X704815Y-335098D01*
G01X712861Y-338098D02*
Y-333098D01*
X714381D01*
X714888Y-333348D01*
X715268Y-333931D01*
X715395Y-334598D01*
X715268Y-335265D01*
X714951Y-335765D01*
X714381Y-336015D01*
X712861D01*
G01X720368Y-338098D02*
Y-334765D01*
G01Y-335348D02*
X720115Y-335015D01*
X719735Y-334848D01*
X719291Y-334765D01*
X718848Y-334931D01*
X718468Y-335265D01*
X718215Y-335765D01*
X718088Y-336431D01*
X718215Y-337098D01*
X718468Y-337598D01*
X718848Y-337931D01*
X719291Y-338098D01*
X719735Y-338015D01*
X720115Y-337765D01*
X720368Y-337431D01*
G01X723251Y-338098D02*
Y-334765D01*
G01Y-335598D02*
X723505Y-335181D01*
X723885Y-334848D01*
X724391Y-334765D01*
X724835Y-334848D01*
X725215Y-335181D01*
X725405Y-335765D01*
Y-338098D01*
G01X728478Y-335848D02*
X730505D01*
X730315Y-335265D01*
X729998Y-334931D01*
X729555Y-334765D01*
X729111Y-334848D01*
X728731Y-335098D01*
X728478Y-335681D01*
X728351Y-336181D01*
Y-336681D01*
X728478Y-337181D01*
X728795Y-337681D01*
X729175Y-338015D01*
X729618Y-338098D01*
X730061Y-337931D01*
X730505Y-337431D01*
G01X734528Y-338098D02*
Y-333098D01*
G01X745235Y-335431D02*
X745488Y-335181D01*
X745678Y-334765D01*
X745805Y-334181D01*
X745678Y-333681D01*
X745425Y-333348D01*
X744981Y-333098D01*
X743271D01*
Y-338098D01*
X745361D01*
X745805Y-337765D01*
X746058Y-337265D01*
X746185Y-336681D01*
X746058Y-336098D01*
X745678Y-335598D01*
X745235Y-335431D01*
X743271D01*
G01X749828Y-338098D02*
X749448Y-338015D01*
X749068Y-337681D01*
X748815Y-337098D01*
X748688Y-336431D01*
X748815Y-335765D01*
X749068Y-335181D01*
X749448Y-334848D01*
X749828Y-334765D01*
X750208Y-334848D01*
X750588Y-335181D01*
X750841Y-335765D01*
X750905Y-336431D01*
X750841Y-337098D01*
X750588Y-337681D01*
X750208Y-338015D01*
X749828Y-338098D01*
G01X756068D02*
Y-334765D01*
G01Y-335348D02*
X755815Y-335015D01*
X755435Y-334848D01*
X754991Y-334765D01*
X754548Y-334931D01*
X754168Y-335265D01*
X753915Y-335765D01*
X753788Y-336431D01*
X753915Y-337098D01*
X754168Y-337598D01*
X754548Y-337931D01*
X754991Y-338098D01*
X755435Y-338015D01*
X755815Y-337765D01*
X756068Y-337431D01*
G01X759141Y-338098D02*
Y-334765D01*
G01Y-335431D02*
X759458Y-335098D01*
X759775Y-334848D01*
X760218Y-334765D01*
X760535Y-334848D01*
X760915Y-335098D01*
G01X766268Y-333098D02*
Y-338098D01*
G01Y-337348D02*
X766015Y-337765D01*
X765635Y-338015D01*
X765191Y-338098D01*
X764685Y-337931D01*
X764305Y-337515D01*
X764051Y-337015D01*
X763988Y-336431D01*
X764051Y-335848D01*
X764305Y-335348D01*
X764685Y-334931D01*
X765191Y-334765D01*
X765635Y-334848D01*
X765951Y-335015D01*
X766268Y-335348D01*
G01X693728Y-320498D02*
Y-325498D01*
G01X692271Y-320498D02*
X695185D01*
G01X698828Y-325498D02*
X698448Y-325415D01*
X698068Y-325081D01*
X697815Y-324498D01*
X697688Y-323831D01*
X697815Y-323165D01*
X698068Y-322581D01*
X698448Y-322248D01*
X698828Y-322165D01*
X699208Y-322248D01*
X699588Y-322581D01*
X699841Y-323165D01*
X699905Y-323831D01*
X699841Y-324498D01*
X699588Y-325081D01*
X699208Y-325415D01*
X698828Y-325498D01*
G01X702788Y-327165D02*
Y-322165D01*
G01Y-322915D02*
X703105Y-322498D01*
X703421Y-322248D01*
X703928Y-322165D01*
X704371Y-322248D01*
X704815Y-322665D01*
X705005Y-323248D01*
X705068Y-323831D01*
X705005Y-324415D01*
X704815Y-324998D01*
X704435Y-325331D01*
X703928Y-325498D01*
X703485Y-325415D01*
X703041Y-325165D01*
X702788Y-324831D01*
G01X712545Y-325498D02*
X714128Y-320498D01*
X715711Y-325498D01*
G01X715141Y-323748D02*
X713115D01*
G01X718151Y-325498D02*
Y-322165D01*
G01Y-322998D02*
X718405Y-322581D01*
X718785Y-322248D01*
X719291Y-322165D01*
X719735Y-322248D01*
X720115Y-322581D01*
X720305Y-323165D01*
Y-325498D01*
G01X725468Y-320498D02*
Y-325498D01*
G01Y-324748D02*
X725215Y-325165D01*
X724835Y-325415D01*
X724391Y-325498D01*
X723885Y-325331D01*
X723505Y-324915D01*
X723251Y-324415D01*
X723188Y-323831D01*
X723251Y-323248D01*
X723505Y-322748D01*
X723885Y-322331D01*
X724391Y-322165D01*
X724835Y-322248D01*
X725151Y-322415D01*
X725468Y-322748D01*
G01X735035Y-322831D02*
X735288Y-322581D01*
X735478Y-322165D01*
X735605Y-321581D01*
X735478Y-321081D01*
X735225Y-320748D01*
X734781Y-320498D01*
X733071D01*
Y-325498D01*
X735161D01*
X735605Y-325165D01*
X735858Y-324665D01*
X735985Y-324081D01*
X735858Y-323498D01*
X735478Y-322998D01*
X735035Y-322831D01*
X733071D01*
G01X739628Y-325498D02*
X739248Y-325415D01*
X738868Y-325081D01*
X738615Y-324498D01*
X738488Y-323831D01*
X738615Y-323165D01*
X738868Y-322581D01*
X739248Y-322248D01*
X739628Y-322165D01*
X740008Y-322248D01*
X740388Y-322581D01*
X740641Y-323165D01*
X740705Y-323831D01*
X740641Y-324498D01*
X740388Y-325081D01*
X740008Y-325415D01*
X739628Y-325498D01*
G01X744728Y-320498D02*
Y-325498D01*
G01X743841Y-322165D02*
X745615D01*
G01X749828Y-320498D02*
Y-325498D01*
G01X748941Y-322165D02*
X750715D01*
G01X754928Y-325498D02*
X754548Y-325415D01*
X754168Y-325081D01*
X753915Y-324498D01*
X753788Y-323831D01*
X753915Y-323165D01*
X754168Y-322581D01*
X754548Y-322248D01*
X754928Y-322165D01*
X755308Y-322248D01*
X755688Y-322581D01*
X755941Y-323165D01*
X756005Y-323831D01*
X755941Y-324498D01*
X755688Y-325081D01*
X755308Y-325415D01*
X754928Y-325498D01*
G01X758128D02*
Y-322165D01*
G01Y-323081D02*
X758318Y-322665D01*
X758635Y-322331D01*
X759078Y-322165D01*
X759521Y-322331D01*
X759838Y-322665D01*
X760028Y-323081D01*
Y-325498D01*
G01Y-323081D02*
X760218Y-322665D01*
X760535Y-322331D01*
X760978Y-322165D01*
X761421Y-322331D01*
X761738Y-322665D01*
X761928Y-323165D01*
Y-325498D01*
G01X768898Y-324831D02*
X769405Y-325248D01*
X769975Y-325498D01*
X770481D01*
X770988Y-325248D01*
X771368Y-324831D01*
X771558Y-324248D01*
X771431Y-323665D01*
X771115Y-323165D01*
X770545Y-322831D01*
X769785Y-322665D01*
X769341Y-322331D01*
X769151Y-321748D01*
X769278Y-321165D01*
X769595Y-320748D01*
X770038Y-320498D01*
X770481D01*
X770925Y-320665D01*
X771305Y-321081D01*
G01X775328Y-322165D02*
Y-325498D01*
G01Y-320831D02*
X775201Y-320748D01*
Y-320581D01*
X775328Y-320498D01*
X775455Y-320581D01*
Y-320748D01*
X775328Y-320831D01*
G01X781568Y-320498D02*
Y-325498D01*
G01Y-324748D02*
X781315Y-325165D01*
X780935Y-325415D01*
X780491Y-325498D01*
X779985Y-325331D01*
X779605Y-324915D01*
X779351Y-324415D01*
X779288Y-323831D01*
X779351Y-323248D01*
X779605Y-322748D01*
X779985Y-322331D01*
X780491Y-322165D01*
X780935Y-322248D01*
X781251Y-322415D01*
X781568Y-322748D01*
G01X784578Y-323248D02*
X786605D01*
X786415Y-322665D01*
X786098Y-322331D01*
X785655Y-322165D01*
X785211Y-322248D01*
X784831Y-322498D01*
X784578Y-323081D01*
X784451Y-323581D01*
Y-324081D01*
X784578Y-324581D01*
X784895Y-325081D01*
X785275Y-325415D01*
X785718Y-325498D01*
X786161Y-325331D01*
X786605Y-324831D01*
G01X692335Y-312898D02*
Y-307898D01*
X693601D01*
X694108Y-308148D01*
X694488Y-308481D01*
X694805Y-308981D01*
X695058Y-309565D01*
X695121Y-310398D01*
X695058Y-311231D01*
X694805Y-311815D01*
X694488Y-312315D01*
X694108Y-312648D01*
X693601Y-312898D01*
X692335D01*
G01X698828Y-309565D02*
Y-312898D01*
G01Y-308231D02*
X698701Y-308148D01*
Y-307981D01*
X698828Y-307898D01*
X698955Y-307981D01*
Y-308148D01*
X698828Y-308231D01*
G01X705068Y-312898D02*
Y-309565D01*
G01Y-310148D02*
X704815Y-309815D01*
X704435Y-309648D01*
X703991Y-309565D01*
X703548Y-309731D01*
X703168Y-310065D01*
X702915Y-310565D01*
X702788Y-311231D01*
X702915Y-311898D01*
X703168Y-312398D01*
X703548Y-312731D01*
X703991Y-312898D01*
X704435Y-312815D01*
X704815Y-312565D01*
X705068Y-312231D01*
G01X707128Y-312898D02*
Y-309565D01*
G01Y-310481D02*
X707318Y-310065D01*
X707635Y-309731D01*
X708078Y-309565D01*
X708521Y-309731D01*
X708838Y-310065D01*
X709028Y-310481D01*
Y-312898D01*
G01Y-310481D02*
X709218Y-310065D01*
X709535Y-309731D01*
X709978Y-309565D01*
X710421Y-309731D01*
X710738Y-310065D01*
X710928Y-310565D01*
Y-312898D01*
G01X713178Y-310648D02*
X715205D01*
X715015Y-310065D01*
X714698Y-309731D01*
X714255Y-309565D01*
X713811Y-309648D01*
X713431Y-309898D01*
X713178Y-310481D01*
X713051Y-310981D01*
Y-311481D01*
X713178Y-311981D01*
X713495Y-312481D01*
X713875Y-312815D01*
X714318Y-312898D01*
X714761Y-312731D01*
X715205Y-312231D01*
G01X719228Y-307898D02*
Y-312898D01*
G01X718341Y-309565D02*
X720115D01*
G01X723378Y-310648D02*
X725405D01*
X725215Y-310065D01*
X724898Y-309731D01*
X724455Y-309565D01*
X724011Y-309648D01*
X723631Y-309898D01*
X723378Y-310481D01*
X723251Y-310981D01*
Y-311481D01*
X723378Y-311981D01*
X723695Y-312481D01*
X724075Y-312815D01*
X724518Y-312898D01*
X724961Y-312731D01*
X725405Y-312231D01*
G01X728541Y-312898D02*
Y-309565D01*
G01Y-310231D02*
X728858Y-309898D01*
X729175Y-309648D01*
X729618Y-309565D01*
X729935Y-309648D01*
X730315Y-309898D01*
G01X738235Y-311898D02*
X738615Y-312481D01*
X739121Y-312815D01*
X739691Y-312898D01*
X740198Y-312815D01*
X740705Y-312398D01*
X741021Y-311898D01*
X741085Y-311398D01*
X740958Y-310815D01*
X740515Y-310398D01*
X740071Y-310231D01*
X739501D01*
G01X740071D02*
X740451Y-309981D01*
X740768Y-309565D01*
X740895Y-309065D01*
X740768Y-308565D01*
X740451Y-308148D01*
X739881Y-307898D01*
X739311Y-307981D01*
X738741Y-308315D01*
G01X742828Y-312898D02*
Y-309565D01*
G01Y-310481D02*
X743018Y-310065D01*
X743335Y-309731D01*
X743778Y-309565D01*
X744221Y-309731D01*
X744538Y-310065D01*
X744728Y-310481D01*
Y-312898D01*
G01Y-310481D02*
X744918Y-310065D01*
X745235Y-309731D01*
X745678Y-309565D01*
X746121Y-309731D01*
X746438Y-310065D01*
X746628Y-310565D01*
Y-312898D01*
G01X747928D02*
Y-309565D01*
G01Y-310481D02*
X748118Y-310065D01*
X748435Y-309731D01*
X748878Y-309565D01*
X749321Y-309731D01*
X749638Y-310065D01*
X749828Y-310481D01*
Y-312898D01*
G01Y-310481D02*
X750018Y-310065D01*
X750335Y-309731D01*
X750778Y-309565D01*
X751221Y-309731D01*
X751538Y-310065D01*
X751728Y-310565D01*
Y-312898D01*
G01X758698Y-312231D02*
X759205Y-312648D01*
X759775Y-312898D01*
X760281D01*
X760788Y-312648D01*
X761168Y-312231D01*
X761358Y-311648D01*
X761231Y-311065D01*
X760915Y-310565D01*
X760345Y-310231D01*
X759585Y-310065D01*
X759141Y-309731D01*
X758951Y-309148D01*
X759078Y-308565D01*
X759395Y-308148D01*
X759838Y-307898D01*
X760281D01*
X760725Y-308065D01*
X761105Y-308481D01*
G01X765128Y-312898D02*
X764748Y-312815D01*
X764368Y-312481D01*
X764115Y-311898D01*
X763988Y-311231D01*
X764115Y-310565D01*
X764368Y-309981D01*
X764748Y-309648D01*
X765128Y-309565D01*
X765508Y-309648D01*
X765888Y-309981D01*
X766141Y-310565D01*
X766205Y-311231D01*
X766141Y-311898D01*
X765888Y-312481D01*
X765508Y-312815D01*
X765128Y-312898D01*
G01X770228D02*
Y-307898D01*
G01X776468D02*
Y-312898D01*
G01Y-312148D02*
X776215Y-312565D01*
X775835Y-312815D01*
X775391Y-312898D01*
X774885Y-312731D01*
X774505Y-312315D01*
X774251Y-311815D01*
X774188Y-311231D01*
X774251Y-310648D01*
X774505Y-310148D01*
X774885Y-309731D01*
X775391Y-309565D01*
X775835Y-309648D01*
X776151Y-309815D01*
X776468Y-310148D01*
G01X779478Y-310648D02*
X781505D01*
X781315Y-310065D01*
X780998Y-309731D01*
X780555Y-309565D01*
X780111Y-309648D01*
X779731Y-309898D01*
X779478Y-310481D01*
X779351Y-310981D01*
Y-311481D01*
X779478Y-311981D01*
X779795Y-312481D01*
X780175Y-312815D01*
X780618Y-312898D01*
X781061Y-312731D01*
X781505Y-312231D01*
G01X784641Y-312898D02*
Y-309565D01*
G01Y-310231D02*
X784958Y-309898D01*
X785275Y-309648D01*
X785718Y-309565D01*
X786035Y-309648D01*
X786415Y-309898D01*
G01X788728Y-312898D02*
Y-309565D01*
G01Y-310481D02*
X788918Y-310065D01*
X789235Y-309731D01*
X789678Y-309565D01*
X790121Y-309731D01*
X790438Y-310065D01*
X790628Y-310481D01*
Y-312898D01*
G01Y-310481D02*
X790818Y-310065D01*
X791135Y-309731D01*
X791578Y-309565D01*
X792021Y-309731D01*
X792338Y-310065D01*
X792528Y-310565D01*
Y-312898D01*
G01X796868D02*
Y-309565D01*
G01Y-310148D02*
X796615Y-309815D01*
X796235Y-309648D01*
X795791Y-309565D01*
X795348Y-309731D01*
X794968Y-310065D01*
X794715Y-310565D01*
X794588Y-311231D01*
X794715Y-311898D01*
X794968Y-312398D01*
X795348Y-312731D01*
X795791Y-312898D01*
X796235Y-312815D01*
X796615Y-312565D01*
X796868Y-312231D01*
G01X799878Y-312315D02*
X800195Y-312648D01*
X800638Y-312898D01*
X801018D01*
X801398Y-312731D01*
X801651Y-312481D01*
X801778Y-312148D01*
X801715Y-311648D01*
X801461Y-311398D01*
X800321Y-310898D01*
X800068Y-310315D01*
X800195Y-309898D01*
X800448Y-309648D01*
X800828Y-309565D01*
X801208Y-309648D01*
X801588Y-309898D01*
G01X804851Y-312898D02*
Y-307898D01*
G01X806878Y-309565D02*
X804851Y-311481D01*
G01X805675Y-310731D02*
X807005Y-312898D01*
G01X616025Y-300298D02*
Y-295298D01*
X618431D01*
G01X617545Y-297715D02*
X616025D01*
G01X622328Y-296965D02*
Y-300298D01*
G01Y-295631D02*
X622201Y-295548D01*
Y-295381D01*
X622328Y-295298D01*
X622455Y-295381D01*
Y-295548D01*
X622328Y-295631D01*
G01X628568Y-295298D02*
Y-300298D01*
G01Y-299548D02*
X628315Y-299965D01*
X627935Y-300215D01*
X627491Y-300298D01*
X626985Y-300131D01*
X626605Y-299715D01*
X626351Y-299215D01*
X626288Y-298631D01*
X626351Y-298048D01*
X626605Y-297548D01*
X626985Y-297131D01*
X627491Y-296965D01*
X627935Y-297048D01*
X628251Y-297215D01*
X628568Y-297548D01*
G01X631451Y-296965D02*
Y-299298D01*
X631705Y-299881D01*
X632085Y-300215D01*
X632528Y-300298D01*
X632971Y-300215D01*
X633351Y-299881D01*
X633605Y-299298D01*
G01Y-300298D02*
Y-296965D01*
G01X638641Y-297381D02*
X638198Y-297048D01*
X637818Y-296965D01*
X637311Y-297131D01*
X636931Y-297465D01*
X636678Y-298048D01*
X636615Y-298631D01*
X636678Y-299215D01*
X636931Y-299715D01*
X637311Y-300131D01*
X637818Y-300298D01*
X638261Y-300131D01*
X638641Y-299798D01*
G01X642728Y-296965D02*
Y-300298D01*
G01Y-295631D02*
X642601Y-295548D01*
Y-295381D01*
X642728Y-295298D01*
X642855Y-295381D01*
Y-295548D01*
X642728Y-295631D01*
G01X648968Y-300298D02*
Y-296965D01*
G01Y-297548D02*
X648715Y-297215D01*
X648335Y-297048D01*
X647891Y-296965D01*
X647448Y-297131D01*
X647068Y-297465D01*
X646815Y-297965D01*
X646688Y-298631D01*
X646815Y-299298D01*
X647068Y-299798D01*
X647448Y-300131D01*
X647891Y-300298D01*
X648335Y-300215D01*
X648715Y-299965D01*
X648968Y-299631D01*
G01X652928Y-300298D02*
Y-295298D01*
G01X661481Y-300298D02*
Y-295298D01*
X663128Y-299465D01*
X664775Y-295298D01*
Y-300298D01*
G01X669368D02*
Y-296965D01*
G01Y-297548D02*
X669115Y-297215D01*
X668735Y-297048D01*
X668291Y-296965D01*
X667848Y-297131D01*
X667468Y-297465D01*
X667215Y-297965D01*
X667088Y-298631D01*
X667215Y-299298D01*
X667468Y-299798D01*
X667848Y-300131D01*
X668291Y-300298D01*
X668735Y-300215D01*
X669115Y-299965D01*
X669368Y-299631D01*
G01X672441Y-300298D02*
Y-296965D01*
G01Y-297631D02*
X672758Y-297298D01*
X673075Y-297048D01*
X673518Y-296965D01*
X673835Y-297048D01*
X674215Y-297298D01*
G01X677351Y-300298D02*
Y-295298D01*
G01X679378Y-296965D02*
X677351Y-298881D01*
G01X678175Y-298131D02*
X679505Y-300298D01*
G01X683528Y-300465D02*
X683401Y-300381D01*
Y-300215D01*
X683528Y-300131D01*
X683655Y-300215D01*
Y-300381D01*
X683528Y-300465D01*
G01Y-298215D02*
X683401Y-298131D01*
Y-297965D01*
X683528Y-297881D01*
X683655Y-297965D01*
Y-298131D01*
X683528Y-298215D01*
G01X692335Y-300298D02*
Y-295298D01*
X693601D01*
X694108Y-295548D01*
X694488Y-295881D01*
X694805Y-296381D01*
X695058Y-296965D01*
X695121Y-297798D01*
X695058Y-298631D01*
X694805Y-299215D01*
X694488Y-299715D01*
X694108Y-300048D01*
X693601Y-300298D01*
X692335D01*
G01X698828Y-296965D02*
Y-300298D01*
G01Y-295631D02*
X698701Y-295548D01*
Y-295381D01*
X698828Y-295298D01*
X698955Y-295381D01*
Y-295548D01*
X698828Y-295631D01*
G01X705068Y-300298D02*
Y-296965D01*
G01Y-297548D02*
X704815Y-297215D01*
X704435Y-297048D01*
X703991Y-296965D01*
X703548Y-297131D01*
X703168Y-297465D01*
X702915Y-297965D01*
X702788Y-298631D01*
X702915Y-299298D01*
X703168Y-299798D01*
X703548Y-300131D01*
X703991Y-300298D01*
X704435Y-300215D01*
X704815Y-299965D01*
X705068Y-299631D01*
G01X707128Y-300298D02*
Y-296965D01*
G01Y-297881D02*
X707318Y-297465D01*
X707635Y-297131D01*
X708078Y-296965D01*
X708521Y-297131D01*
X708838Y-297465D01*
X709028Y-297881D01*
Y-300298D01*
G01Y-297881D02*
X709218Y-297465D01*
X709535Y-297131D01*
X709978Y-296965D01*
X710421Y-297131D01*
X710738Y-297465D01*
X710928Y-297965D01*
Y-300298D01*
G01X713178Y-298048D02*
X715205D01*
X715015Y-297465D01*
X714698Y-297131D01*
X714255Y-296965D01*
X713811Y-297048D01*
X713431Y-297298D01*
X713178Y-297881D01*
X713051Y-298381D01*
Y-298881D01*
X713178Y-299381D01*
X713495Y-299881D01*
X713875Y-300215D01*
X714318Y-300298D01*
X714761Y-300131D01*
X715205Y-299631D01*
G01X719228Y-295298D02*
Y-300298D01*
G01X718341Y-296965D02*
X720115D01*
G01X723378Y-298048D02*
X725405D01*
X725215Y-297465D01*
X724898Y-297131D01*
X724455Y-296965D01*
X724011Y-297048D01*
X723631Y-297298D01*
X723378Y-297881D01*
X723251Y-298381D01*
Y-298881D01*
X723378Y-299381D01*
X723695Y-299881D01*
X724075Y-300215D01*
X724518Y-300298D01*
X724961Y-300131D01*
X725405Y-299631D01*
G01X728541Y-300298D02*
Y-296965D01*
G01Y-297631D02*
X728858Y-297298D01*
X729175Y-297048D01*
X729618Y-296965D01*
X729935Y-297048D01*
X730315Y-297298D01*
G01X739628Y-300298D02*
Y-295298D01*
X738868Y-296298D01*
G01Y-300298D02*
X740388D01*
G01X742828D02*
Y-296965D01*
G01Y-297881D02*
X743018Y-297465D01*
X743335Y-297131D01*
X743778Y-296965D01*
X744221Y-297131D01*
X744538Y-297465D01*
X744728Y-297881D01*
Y-300298D01*
G01Y-297881D02*
X744918Y-297465D01*
X745235Y-297131D01*
X745678Y-296965D01*
X746121Y-297131D01*
X746438Y-297465D01*
X746628Y-297965D01*
Y-300298D01*
G01X747928D02*
Y-296965D01*
G01Y-297881D02*
X748118Y-297465D01*
X748435Y-297131D01*
X748878Y-296965D01*
X749321Y-297131D01*
X749638Y-297465D01*
X749828Y-297881D01*
Y-300298D01*
G01Y-297881D02*
X750018Y-297465D01*
X750335Y-297131D01*
X750778Y-296965D01*
X751221Y-297131D01*
X751538Y-297465D01*
X751728Y-297965D01*
Y-300298D01*
G01X761421Y-295715D02*
X761041Y-295465D01*
X760598Y-295298D01*
X760091D01*
X759521Y-295548D01*
X759078Y-295965D01*
X758761Y-296465D01*
X758508Y-297298D01*
X758445Y-298048D01*
X758571Y-298798D01*
X758761Y-299298D01*
X759141Y-299798D01*
X759585Y-300131D01*
X760028Y-300298D01*
X760471D01*
X760915Y-300131D01*
X761295Y-299881D01*
X761611Y-299548D01*
G01X765128Y-300298D02*
X764748Y-300215D01*
X764368Y-299881D01*
X764115Y-299298D01*
X763988Y-298631D01*
X764115Y-297965D01*
X764368Y-297381D01*
X764748Y-297048D01*
X765128Y-296965D01*
X765508Y-297048D01*
X765888Y-297381D01*
X766141Y-297965D01*
X766205Y-298631D01*
X766141Y-299298D01*
X765888Y-299881D01*
X765508Y-300215D01*
X765128Y-300298D01*
G01X769088Y-301965D02*
Y-296965D01*
G01Y-297715D02*
X769405Y-297298D01*
X769721Y-297048D01*
X770228Y-296965D01*
X770671Y-297048D01*
X771115Y-297465D01*
X771305Y-298048D01*
X771368Y-298631D01*
X771305Y-299215D01*
X771115Y-299798D01*
X770735Y-300131D01*
X770228Y-300298D01*
X769785Y-300215D01*
X769341Y-299965D01*
X769088Y-299631D01*
G01X774188Y-301965D02*
Y-296965D01*
G01Y-297715D02*
X774505Y-297298D01*
X774821Y-297048D01*
X775328Y-296965D01*
X775771Y-297048D01*
X776215Y-297465D01*
X776405Y-298048D01*
X776468Y-298631D01*
X776405Y-299215D01*
X776215Y-299798D01*
X775835Y-300131D01*
X775328Y-300298D01*
X774885Y-300215D01*
X774441Y-299965D01*
X774188Y-299631D01*
G01X779478Y-298048D02*
X781505D01*
X781315Y-297465D01*
X780998Y-297131D01*
X780555Y-296965D01*
X780111Y-297048D01*
X779731Y-297298D01*
X779478Y-297881D01*
X779351Y-298381D01*
Y-298881D01*
X779478Y-299381D01*
X779795Y-299881D01*
X780175Y-300215D01*
X780618Y-300298D01*
X781061Y-300131D01*
X781505Y-299631D01*
G01X784641Y-300298D02*
Y-296965D01*
G01Y-297631D02*
X784958Y-297298D01*
X785275Y-297048D01*
X785718Y-296965D01*
X786035Y-297048D01*
X786415Y-297298D01*
G01X689416Y-238606D02*
Y-243606D01*
G01X687959Y-238606D02*
X690873D01*
G01X694516Y-243606D02*
X694136Y-243523D01*
X693756Y-243189D01*
X693503Y-242606D01*
X693376Y-241939D01*
X693503Y-241273D01*
X693756Y-240689D01*
X694136Y-240356D01*
X694516Y-240273D01*
X694896Y-240356D01*
X695276Y-240689D01*
X695529Y-241273D01*
X695593Y-241939D01*
X695529Y-242606D01*
X695276Y-243189D01*
X694896Y-243523D01*
X694516Y-243606D01*
G01X699616D02*
Y-238606D01*
G01X703766Y-241356D02*
X705793D01*
X705603Y-240773D01*
X705286Y-240439D01*
X704843Y-240273D01*
X704399Y-240356D01*
X704019Y-240606D01*
X703766Y-241189D01*
X703639Y-241689D01*
Y-242189D01*
X703766Y-242689D01*
X704083Y-243189D01*
X704463Y-243523D01*
X704906Y-243606D01*
X705349Y-243439D01*
X705793Y-242939D01*
G01X708929Y-243606D02*
Y-240273D01*
G01Y-240939D02*
X709246Y-240606D01*
X709563Y-240356D01*
X710006Y-240273D01*
X710323Y-240356D01*
X710703Y-240606D01*
G01X716056Y-243606D02*
Y-240273D01*
G01Y-240856D02*
X715803Y-240523D01*
X715423Y-240356D01*
X714979Y-240273D01*
X714536Y-240439D01*
X714156Y-240773D01*
X713903Y-241273D01*
X713776Y-241939D01*
X713903Y-242606D01*
X714156Y-243106D01*
X714536Y-243439D01*
X714979Y-243606D01*
X715423Y-243523D01*
X715803Y-243273D01*
X716056Y-242939D01*
G01X718939Y-243606D02*
Y-240273D01*
G01Y-241106D02*
X719193Y-240689D01*
X719573Y-240356D01*
X720079Y-240273D01*
X720523Y-240356D01*
X720903Y-240689D01*
X721093Y-241273D01*
Y-243606D01*
G01X726129Y-240689D02*
X725686Y-240356D01*
X725306Y-240273D01*
X724799Y-240439D01*
X724419Y-240773D01*
X724166Y-241356D01*
X724103Y-241939D01*
X724166Y-242523D01*
X724419Y-243023D01*
X724799Y-243439D01*
X725306Y-243606D01*
X725749Y-243439D01*
X726129Y-243106D01*
G01X729266Y-241356D02*
X731293D01*
X731103Y-240773D01*
X730786Y-240439D01*
X730343Y-240273D01*
X729899Y-240356D01*
X729519Y-240606D01*
X729266Y-241189D01*
X729139Y-241689D01*
Y-242189D01*
X729266Y-242689D01*
X729583Y-243189D01*
X729963Y-243523D01*
X730406Y-243606D01*
X730849Y-243439D01*
X731293Y-242939D01*
G01X739719Y-241939D02*
X741239D01*
G01X740416Y-240856D02*
Y-243023D01*
G01X745516Y-238606D02*
X745009Y-238773D01*
X744629Y-239189D01*
X744376Y-239689D01*
X744186Y-240356D01*
X744123Y-241106D01*
X744186Y-241856D01*
X744376Y-242523D01*
X744629Y-243023D01*
X745009Y-243439D01*
X745516Y-243606D01*
X746023Y-243439D01*
X746403Y-243023D01*
X746656Y-242523D01*
X746846Y-241856D01*
X746909Y-241106D01*
X746846Y-240356D01*
X746656Y-239689D01*
X746403Y-239189D01*
X746023Y-238773D01*
X745516Y-238606D01*
G01X750616Y-243773D02*
X750489Y-243689D01*
Y-243523D01*
X750616Y-243439D01*
X750743Y-243523D01*
Y-243689D01*
X750616Y-243773D01*
G01X755716Y-238606D02*
X755209Y-238773D01*
X754829Y-239189D01*
X754576Y-239689D01*
X754386Y-240356D01*
X754323Y-241106D01*
X754386Y-241856D01*
X754576Y-242523D01*
X754829Y-243023D01*
X755209Y-243439D01*
X755716Y-243606D01*
X756223Y-243439D01*
X756603Y-243023D01*
X756856Y-242523D01*
X757046Y-241856D01*
X757109Y-241106D01*
X757046Y-240356D01*
X756856Y-239689D01*
X756603Y-239189D01*
X756223Y-238773D01*
X755716Y-238606D01*
G01X759423Y-242856D02*
X759803Y-243273D01*
X760246Y-243523D01*
X760816Y-243606D01*
X761386Y-243439D01*
X761829Y-243106D01*
X762146Y-242523D01*
X762209Y-241856D01*
X762083Y-241189D01*
X761766Y-240773D01*
X761323Y-240439D01*
X760879Y-240356D01*
X760436Y-240439D01*
X759866Y-240773D01*
X760056Y-238606D01*
X761766D01*
G01X765916D02*
X765409Y-238773D01*
X765029Y-239189D01*
X764776Y-239689D01*
X764586Y-240356D01*
X764523Y-241106D01*
X764586Y-241856D01*
X764776Y-242523D01*
X765029Y-243023D01*
X765409Y-243439D01*
X765916Y-243606D01*
X766423Y-243439D01*
X766803Y-243023D01*
X767056Y-242523D01*
X767246Y-241856D01*
X767309Y-241106D01*
X767246Y-240356D01*
X767056Y-239689D01*
X766803Y-239189D01*
X766423Y-238773D01*
X765916Y-238606D01*
G01X771016Y-243606D02*
X771459Y-243523D01*
X771966Y-243273D01*
X772283Y-242856D01*
X772409Y-242273D01*
X772283Y-241689D01*
X771903Y-241189D01*
X771333Y-240939D01*
X770699D01*
X770319Y-240773D01*
X770003Y-240356D01*
X769876Y-239773D01*
X770066Y-239189D01*
X770509Y-238773D01*
X771016Y-238606D01*
X771523Y-238773D01*
X771966Y-239189D01*
X772156Y-239773D01*
X772029Y-240356D01*
X771713Y-240773D01*
X771333Y-240939D01*
X770699D01*
X770129Y-241189D01*
X769749Y-241689D01*
X769623Y-242273D01*
X769749Y-242856D01*
X770066Y-243273D01*
X770573Y-243523D01*
X771016Y-243606D01*
G01X774216D02*
Y-240273D01*
G01Y-241189D02*
X774406Y-240773D01*
X774723Y-240439D01*
X775166Y-240273D01*
X775609Y-240439D01*
X775926Y-240773D01*
X776116Y-241189D01*
Y-243606D01*
G01Y-241189D02*
X776306Y-240773D01*
X776623Y-240439D01*
X777066Y-240273D01*
X777509Y-240439D01*
X777826Y-240773D01*
X778016Y-241273D01*
Y-243606D01*
G01X779316D02*
Y-240273D01*
G01Y-241189D02*
X779506Y-240773D01*
X779823Y-240439D01*
X780266Y-240273D01*
X780709Y-240439D01*
X781026Y-240773D01*
X781216Y-241189D01*
Y-243606D01*
G01Y-241189D02*
X781406Y-240773D01*
X781723Y-240439D01*
X782166Y-240273D01*
X782609Y-240439D01*
X782926Y-240773D01*
X783116Y-241273D01*
Y-243606D01*
G01X785176Y-243773D02*
X787456Y-238606D01*
G01X790593Y-241939D02*
X792239D01*
G01X796516Y-238606D02*
X796009Y-238773D01*
X795629Y-239189D01*
X795376Y-239689D01*
X795186Y-240356D01*
X795123Y-241106D01*
X795186Y-241856D01*
X795376Y-242523D01*
X795629Y-243023D01*
X796009Y-243439D01*
X796516Y-243606D01*
X797023Y-243439D01*
X797403Y-243023D01*
X797656Y-242523D01*
X797846Y-241856D01*
X797909Y-241106D01*
X797846Y-240356D01*
X797656Y-239689D01*
X797403Y-239189D01*
X797023Y-238773D01*
X796516Y-238606D01*
G01X801616Y-243773D02*
X801489Y-243689D01*
Y-243523D01*
X801616Y-243439D01*
X801743Y-243523D01*
Y-243689D01*
X801616Y-243773D01*
G01X806716Y-238606D02*
X806209Y-238773D01*
X805829Y-239189D01*
X805576Y-239689D01*
X805386Y-240356D01*
X805323Y-241106D01*
X805386Y-241856D01*
X805576Y-242523D01*
X805829Y-243023D01*
X806209Y-243439D01*
X806716Y-243606D01*
X807223Y-243439D01*
X807603Y-243023D01*
X807856Y-242523D01*
X808046Y-241856D01*
X808109Y-241106D01*
X808046Y-240356D01*
X807856Y-239689D01*
X807603Y-239189D01*
X807223Y-238773D01*
X806716Y-238606D01*
G01X811816D02*
X811309Y-238773D01*
X810929Y-239189D01*
X810676Y-239689D01*
X810486Y-240356D01*
X810423Y-241106D01*
X810486Y-241856D01*
X810676Y-242523D01*
X810929Y-243023D01*
X811309Y-243439D01*
X811816Y-243606D01*
X812323Y-243439D01*
X812703Y-243023D01*
X812956Y-242523D01*
X813146Y-241856D01*
X813209Y-241106D01*
X813146Y-240356D01*
X812956Y-239689D01*
X812703Y-239189D01*
X812323Y-238773D01*
X811816Y-238606D01*
G01X816916D02*
X816409Y-238773D01*
X816029Y-239189D01*
X815776Y-239689D01*
X815586Y-240356D01*
X815523Y-241106D01*
X815586Y-241856D01*
X815776Y-242523D01*
X816029Y-243023D01*
X816409Y-243439D01*
X816916Y-243606D01*
X817423Y-243439D01*
X817803Y-243023D01*
X818056Y-242523D01*
X818246Y-241856D01*
X818309Y-241106D01*
X818246Y-240356D01*
X818056Y-239689D01*
X817803Y-239189D01*
X817423Y-238773D01*
X816916Y-238606D01*
G01X822016D02*
X821509Y-238773D01*
X821129Y-239189D01*
X820876Y-239689D01*
X820686Y-240356D01*
X820623Y-241106D01*
X820686Y-241856D01*
X820876Y-242523D01*
X821129Y-243023D01*
X821509Y-243439D01*
X822016Y-243606D01*
X822523Y-243439D01*
X822903Y-243023D01*
X823156Y-242523D01*
X823346Y-241856D01*
X823409Y-241106D01*
X823346Y-240356D01*
X823156Y-239689D01*
X822903Y-239189D01*
X822523Y-238773D01*
X822016Y-238606D01*
G01X825216Y-243606D02*
Y-240273D01*
G01Y-241189D02*
X825406Y-240773D01*
X825723Y-240439D01*
X826166Y-240273D01*
X826609Y-240439D01*
X826926Y-240773D01*
X827116Y-241189D01*
Y-243606D01*
G01Y-241189D02*
X827306Y-240773D01*
X827623Y-240439D01*
X828066Y-240273D01*
X828509Y-240439D01*
X828826Y-240773D01*
X829016Y-241273D01*
Y-243606D01*
G01X830316D02*
Y-240273D01*
G01Y-241189D02*
X830506Y-240773D01*
X830823Y-240439D01*
X831266Y-240273D01*
X831709Y-240439D01*
X832026Y-240773D01*
X832216Y-241189D01*
Y-243606D01*
G01Y-241189D02*
X832406Y-240773D01*
X832723Y-240439D01*
X833166Y-240273D01*
X833609Y-240439D01*
X833926Y-240773D01*
X834116Y-241273D01*
Y-243606D01*
G01X618016Y-226006D02*
Y-231006D01*
G01X616559Y-226006D02*
X619473D01*
G01X623116Y-231006D02*
X622736Y-230923D01*
X622356Y-230589D01*
X622103Y-230006D01*
X621976Y-229339D01*
X622103Y-228673D01*
X622356Y-228089D01*
X622736Y-227756D01*
X623116Y-227673D01*
X623496Y-227756D01*
X623876Y-228089D01*
X624129Y-228673D01*
X624193Y-229339D01*
X624129Y-230006D01*
X623876Y-230589D01*
X623496Y-230923D01*
X623116Y-231006D01*
G01X628216D02*
X627836Y-230923D01*
X627456Y-230589D01*
X627203Y-230006D01*
X627076Y-229339D01*
X627203Y-228673D01*
X627456Y-228089D01*
X627836Y-227756D01*
X628216Y-227673D01*
X628596Y-227756D01*
X628976Y-228089D01*
X629229Y-228673D01*
X629293Y-229339D01*
X629229Y-230006D01*
X628976Y-230589D01*
X628596Y-230923D01*
X628216Y-231006D01*
G01X633316D02*
Y-226006D01*
G01X638416Y-227673D02*
Y-231006D01*
G01Y-226339D02*
X638289Y-226256D01*
Y-226089D01*
X638416Y-226006D01*
X638543Y-226089D01*
Y-226256D01*
X638416Y-226339D01*
G01X642439Y-231006D02*
Y-227673D01*
G01Y-228506D02*
X642693Y-228089D01*
X643073Y-227756D01*
X643579Y-227673D01*
X644023Y-227756D01*
X644403Y-228089D01*
X644593Y-228673D01*
Y-231006D01*
G01X647729Y-232256D02*
X648173Y-232589D01*
X648679Y-232673D01*
X649123Y-232589D01*
X649503Y-232173D01*
X649756Y-231589D01*
Y-227673D01*
G01Y-228339D02*
X649503Y-228006D01*
X649123Y-227756D01*
X648679Y-227673D01*
X648173Y-227839D01*
X647856Y-228173D01*
X647603Y-228756D01*
X647476Y-229339D01*
X647539Y-229839D01*
X647793Y-230423D01*
X648173Y-230839D01*
X648679Y-231006D01*
X649059Y-230923D01*
X649503Y-230589D01*
X649756Y-230256D01*
G01X657486Y-231006D02*
Y-226006D01*
G01X660146D02*
Y-231006D01*
G01Y-228506D02*
X657486D01*
G01X663916Y-231006D02*
X663536Y-230923D01*
X663156Y-230589D01*
X662903Y-230006D01*
X662776Y-229339D01*
X662903Y-228673D01*
X663156Y-228089D01*
X663536Y-227756D01*
X663916Y-227673D01*
X664296Y-227756D01*
X664676Y-228089D01*
X664929Y-228673D01*
X664993Y-229339D01*
X664929Y-230006D01*
X664676Y-230589D01*
X664296Y-230923D01*
X663916Y-231006D01*
G01X669016D02*
Y-226006D01*
G01X673166Y-228756D02*
X675193D01*
X675003Y-228173D01*
X674686Y-227839D01*
X674243Y-227673D01*
X673799Y-227756D01*
X673419Y-228006D01*
X673166Y-228589D01*
X673039Y-229089D01*
Y-229589D01*
X673166Y-230089D01*
X673483Y-230589D01*
X673863Y-230923D01*
X674306Y-231006D01*
X674749Y-230839D01*
X675193Y-230339D01*
G01X679216Y-231173D02*
X679089Y-231089D01*
Y-230923D01*
X679216Y-230839D01*
X679343Y-230923D01*
Y-231089D01*
X679216Y-231173D01*
G01Y-228923D02*
X679089Y-228839D01*
Y-228673D01*
X679216Y-228589D01*
X679343Y-228673D01*
Y-228839D01*
X679216Y-228923D01*
G01X688023Y-231006D02*
Y-226006D01*
X689289D01*
X689796Y-226256D01*
X690176Y-226589D01*
X690493Y-227089D01*
X690746Y-227673D01*
X690809Y-228506D01*
X690746Y-229339D01*
X690493Y-229923D01*
X690176Y-230423D01*
X689796Y-230756D01*
X689289Y-231006D01*
X688023D01*
G01X694516Y-227673D02*
Y-231006D01*
G01Y-226339D02*
X694389Y-226256D01*
Y-226089D01*
X694516Y-226006D01*
X694643Y-226089D01*
Y-226256D01*
X694516Y-226339D01*
G01X700756Y-231006D02*
Y-227673D01*
G01Y-228256D02*
X700503Y-227923D01*
X700123Y-227756D01*
X699679Y-227673D01*
X699236Y-227839D01*
X698856Y-228173D01*
X698603Y-228673D01*
X698476Y-229339D01*
X698603Y-230006D01*
X698856Y-230506D01*
X699236Y-230839D01*
X699679Y-231006D01*
X700123Y-230923D01*
X700503Y-230673D01*
X700756Y-230339D01*
G01X702816Y-231006D02*
Y-227673D01*
G01Y-228589D02*
X703006Y-228173D01*
X703323Y-227839D01*
X703766Y-227673D01*
X704209Y-227839D01*
X704526Y-228173D01*
X704716Y-228589D01*
Y-231006D01*
G01Y-228589D02*
X704906Y-228173D01*
X705223Y-227839D01*
X705666Y-227673D01*
X706109Y-227839D01*
X706426Y-228173D01*
X706616Y-228673D01*
Y-231006D01*
G01X708866Y-228756D02*
X710893D01*
X710703Y-228173D01*
X710386Y-227839D01*
X709943Y-227673D01*
X709499Y-227756D01*
X709119Y-228006D01*
X708866Y-228589D01*
X708739Y-229089D01*
Y-229589D01*
X708866Y-230089D01*
X709183Y-230589D01*
X709563Y-230923D01*
X710006Y-231006D01*
X710449Y-230839D01*
X710893Y-230339D01*
G01X714916Y-226006D02*
Y-231006D01*
G01X714029Y-227673D02*
X715803D01*
G01X719066Y-228756D02*
X721093D01*
X720903Y-228173D01*
X720586Y-227839D01*
X720143Y-227673D01*
X719699Y-227756D01*
X719319Y-228006D01*
X719066Y-228589D01*
X718939Y-229089D01*
Y-229589D01*
X719066Y-230089D01*
X719383Y-230589D01*
X719763Y-230923D01*
X720206Y-231006D01*
X720649Y-230839D01*
X721093Y-230339D01*
G01X724229Y-231006D02*
Y-227673D01*
G01Y-228339D02*
X724546Y-228006D01*
X724863Y-227756D01*
X725306Y-227673D01*
X725623Y-227756D01*
X726003Y-228006D01*
G01X733923Y-230006D02*
X734303Y-230589D01*
X734809Y-230923D01*
X735379Y-231006D01*
X735886Y-230923D01*
X736393Y-230506D01*
X736709Y-230006D01*
X736773Y-229506D01*
X736646Y-228923D01*
X736203Y-228506D01*
X735759Y-228339D01*
X735189D01*
G01X735759D02*
X736139Y-228089D01*
X736456Y-227673D01*
X736583Y-227173D01*
X736456Y-226673D01*
X736139Y-226256D01*
X735569Y-226006D01*
X734999Y-226089D01*
X734429Y-226423D01*
G01X740416Y-231173D02*
X740289Y-231089D01*
Y-230923D01*
X740416Y-230839D01*
X740543Y-230923D01*
Y-231089D01*
X740416Y-231173D01*
G01X745516Y-231006D02*
Y-226006D01*
X744756Y-227006D01*
G01Y-231006D02*
X746276D01*
G01X750489D02*
X750616Y-229923D01*
X750806Y-229006D01*
X751059Y-228173D01*
X751376Y-227256D01*
X751883Y-226006D01*
X749349D01*
G01X754323Y-230256D02*
X754703Y-230673D01*
X755146Y-230923D01*
X755716Y-231006D01*
X756286Y-230839D01*
X756729Y-230506D01*
X757046Y-229923D01*
X757109Y-229256D01*
X756983Y-228589D01*
X756666Y-228173D01*
X756223Y-227839D01*
X755779Y-227756D01*
X755336Y-227839D01*
X754766Y-228173D01*
X754956Y-226006D01*
X756666D01*
G01X758916Y-231006D02*
Y-227673D01*
G01Y-228589D02*
X759106Y-228173D01*
X759423Y-227839D01*
X759866Y-227673D01*
X760309Y-227839D01*
X760626Y-228173D01*
X760816Y-228589D01*
Y-231006D01*
G01Y-228589D02*
X761006Y-228173D01*
X761323Y-227839D01*
X761766Y-227673D01*
X762209Y-227839D01*
X762526Y-228173D01*
X762716Y-228673D01*
Y-231006D01*
G01X764016D02*
Y-227673D01*
G01Y-228589D02*
X764206Y-228173D01*
X764523Y-227839D01*
X764966Y-227673D01*
X765409Y-227839D01*
X765726Y-228173D01*
X765916Y-228589D01*
Y-231006D01*
G01Y-228589D02*
X766106Y-228173D01*
X766423Y-227839D01*
X766866Y-227673D01*
X767309Y-227839D01*
X767626Y-228173D01*
X767816Y-228673D01*
Y-231006D01*
G01X774659D02*
Y-226006D01*
X777573Y-231006D01*
Y-226006D01*
G01X779949Y-231006D02*
Y-226006D01*
X781469D01*
X781976Y-226256D01*
X782356Y-226839D01*
X782483Y-227506D01*
X782356Y-228173D01*
X782039Y-228673D01*
X781469Y-228923D01*
X779949D01*
G01X786316Y-226006D02*
Y-231006D01*
G01X784859Y-226006D02*
X787773D01*
G01X790086Y-231006D02*
Y-226006D01*
G01X792746D02*
Y-231006D01*
G01Y-228506D02*
X790086D01*
G01X644423Y-450298D02*
X643439Y-444392D01*
X642454Y-450298D01*
X644423D01*
G01X643439Y-440455D02*
Y-444392D01*
G01X658006D02*
X643045D01*
G01X636772Y-441658D02*
X636272Y-441278D01*
X636022Y-440835D01*
X635939Y-440328D01*
X636106Y-439695D01*
X636522Y-439252D01*
X637022Y-439125D01*
X637522Y-439188D01*
X637939Y-439442D01*
X638772Y-440708D01*
X639356Y-441278D01*
X640189Y-441658D01*
X640939Y-441785D01*
Y-439125D01*
G01X642454Y-430613D02*
X643439Y-436518D01*
X644423Y-430613D01*
X642454D01*
G01X643439Y-440455D02*
Y-436518D01*
G01X658006D02*
X643045D01*
G01X645269Y-363778D02*
X658732Y-385319D01*
G01X657858Y-379203D02*
X662098Y-376553D01*
X660847Y-376439D01*
G01X657455Y-378559D02*
X658261Y-379848D01*
G01X649234Y-368264D02*
X645269Y-363778D01*
X647565Y-369307D01*
X649234Y-368264D01*
G01X661462Y-373177D02*
X652452Y-372912D01*
G01X659457Y-373044D02*
G03I-2500J0D01*
G01X650818Y-361223D02*
X681147Y-354224D01*
G01X656351Y-358936D02*
X650818Y-361223D01*
X656794Y-360854D01*
X656351Y-358936D01*
G01X650564Y-263436D02*
X694667Y-253671D01*
G01X656118Y-261198D02*
X650564Y-263436D01*
X656543Y-263120D01*
X656118Y-261198D01*
G01X666667Y-463093D02*
X672572Y-462109D01*
X666667Y-461124D01*
Y-463093D01*
G01X678872Y-462109D02*
X672572D01*
G01Y-442817D02*
Y-462502D01*
G01X673497Y-352398D02*
X673998Y-352881D01*
X674567Y-353092D01*
X675141Y-353045D01*
X675616Y-352849D01*
X676016Y-352330D01*
X676212Y-351771D01*
X676161Y-351270D01*
X675907Y-350730D01*
X675381Y-350424D01*
X674912Y-350361D01*
X674356Y-350489D01*
G01X674912Y-350361D02*
X675226Y-350032D01*
X675441Y-349555D01*
X675452Y-349039D01*
X675216Y-348580D01*
X674814Y-348245D01*
X674202Y-348130D01*
X673665Y-348339D01*
X673185Y-348792D01*
G01X670556Y-347689D02*
X667371Y-356120D01*
G01X671464Y-351905D02*
G03I-2501J0D01*
G01X667116Y-256186D02*
X667613Y-256674D01*
X668179Y-256889D01*
X668754Y-256848D01*
X669231Y-256657D01*
X669635Y-256140D01*
X669836Y-255584D01*
X669790Y-255082D01*
X669540Y-254540D01*
X669017Y-254229D01*
X668548Y-254162D01*
X667992Y-254285D01*
G01X668548Y-254162D02*
X668865Y-253836D01*
X669085Y-253360D01*
X669100Y-252845D01*
X668868Y-252384D01*
X668469Y-252046D01*
X667859Y-251925D01*
X667320Y-252129D01*
X666836Y-252578D01*
G01X673707Y-255922D02*
X673565Y-255868D01*
X673529Y-255705D01*
X673635Y-255597D01*
X673777Y-255651D01*
X673813Y-255813D01*
X673707Y-255922D01*
G01X678650Y-254657D02*
X677569Y-249776D01*
X677043Y-250916D01*
G01X677908Y-254822D02*
X679392Y-254493D01*
G01X683505Y-253583D02*
X683395Y-252498D01*
X683382Y-251562D01*
X683449Y-250693D01*
X683561Y-249730D01*
X683785Y-248400D01*
X681312Y-248947D01*
G01X687086Y-252022D02*
X687547Y-252347D01*
X688033Y-252495D01*
X688608Y-252453D01*
X689129Y-252167D01*
X689489Y-251746D01*
X689672Y-251108D01*
X689590Y-250444D01*
X689322Y-249820D01*
X688923Y-249482D01*
X688418Y-249252D01*
X687967Y-249267D01*
X687553Y-249444D01*
X687068Y-249892D01*
X686785Y-247736D01*
X688455Y-247366D01*
G01X664217Y-251451D02*
X660956Y-259854D01*
G01X665086Y-255653D02*
G03I-2500J0D01*
G01X677479Y-458609D02*
X677859Y-459192D01*
X678365Y-459526D01*
X678935Y-459609D01*
X679442Y-459526D01*
X679949Y-459109D01*
X680265Y-458609D01*
X680329Y-458109D01*
X680202Y-457526D01*
X679759Y-457109D01*
X679315Y-456942D01*
X678745D01*
G01X679315D02*
X679695Y-456692D01*
X680012Y-456276D01*
X680139Y-455776D01*
X680012Y-455276D01*
X679695Y-454859D01*
X679125Y-454609D01*
X678555Y-454692D01*
X677985Y-455026D01*
G01X690289Y-461124D02*
X684383Y-462109D01*
X690289Y-463093D01*
Y-461124D01*
G01X678872Y-462109D02*
X684383D01*
G01Y-442817D02*
Y-462502D01*
G01X792890Y-506597D02*
Y-501597D01*
X794410D01*
X794917Y-501847D01*
X795297Y-502430D01*
X795424Y-503097D01*
X795297Y-503764D01*
X794980Y-504264D01*
X794410Y-504514D01*
X792890D01*
G01X800397Y-506597D02*
Y-503264D01*
G01Y-503847D02*
X800144Y-503514D01*
X799764Y-503347D01*
X799320Y-503264D01*
X798877Y-503430D01*
X798497Y-503764D01*
X798244Y-504264D01*
X798117Y-504930D01*
X798244Y-505597D01*
X798497Y-506097D01*
X798877Y-506430D01*
X799320Y-506597D01*
X799764Y-506514D01*
X800144Y-506264D01*
X800397Y-505930D01*
G01X803280Y-506597D02*
Y-503264D01*
G01Y-504097D02*
X803534Y-503680D01*
X803914Y-503347D01*
X804420Y-503264D01*
X804864Y-503347D01*
X805244Y-503680D01*
X805434Y-504264D01*
Y-506597D01*
G01X808507Y-504347D02*
X810534D01*
X810344Y-503764D01*
X810027Y-503430D01*
X809584Y-503264D01*
X809140Y-503347D01*
X808760Y-503597D01*
X808507Y-504180D01*
X808380Y-504680D01*
Y-505180D01*
X808507Y-505680D01*
X808824Y-506180D01*
X809204Y-506514D01*
X809647Y-506597D01*
X810090Y-506430D01*
X810534Y-505930D01*
G01X814557Y-506597D02*
Y-501597D01*
G01X823490Y-506597D02*
Y-501597D01*
X825074D01*
X825580Y-501847D01*
X825897Y-502180D01*
X826024Y-502847D01*
X825897Y-503514D01*
X825517Y-503930D01*
X825074Y-504180D01*
X823490D01*
G01X825074D02*
X826024Y-506597D01*
G01X828907Y-504347D02*
X830934D01*
X830744Y-503764D01*
X830427Y-503430D01*
X829984Y-503264D01*
X829540Y-503347D01*
X829160Y-503597D01*
X828907Y-504180D01*
X828780Y-504680D01*
Y-505180D01*
X828907Y-505680D01*
X829224Y-506180D01*
X829604Y-506514D01*
X830047Y-506597D01*
X830490Y-506430D01*
X830934Y-505930D01*
G01X833817Y-503264D02*
X834957Y-506597D01*
X836097Y-503264D01*
G01X845664Y-503930D02*
X845917Y-503680D01*
X846107Y-503264D01*
X846234Y-502680D01*
X846107Y-502180D01*
X845854Y-501847D01*
X845410Y-501597D01*
X843700D01*
Y-506597D01*
X845790D01*
X846234Y-506264D01*
X846487Y-505764D01*
X846614Y-505180D01*
X846487Y-504597D01*
X846107Y-504097D01*
X845664Y-503930D01*
X843700D01*
G01X2010999Y-388000D02*
Y1475775D01*
X-407000D01*
Y-386798D01*
Y-755294D01*
Y-793716D01*
X-368578D01*
X1942346D01*
X2010999D01*
Y-725063D01*
Y-388000D01*
G01X-51939Y-498031D02*
G03I-6250J0D01*
G01X-52284Y426772D02*
G03I-5905J0D01*
G01X-51939Y454331D02*
G03I-6250J0D01*
G01X-42602Y-671096D02*
X-41975Y-671621D01*
X-41270Y-671936D01*
X-40644D01*
X-40017Y-671621D01*
X-39547Y-671096D01*
X-39312Y-670361D01*
X-39469Y-669626D01*
X-39860Y-668996D01*
X-40565Y-668576D01*
X-41505Y-668366D01*
X-42054Y-667946D01*
X-42289Y-667211D01*
X-42132Y-666476D01*
X-41740Y-665951D01*
X-41192Y-665636D01*
X-40644D01*
X-40095Y-665846D01*
X-39625Y-666371D01*
G01X-36302Y-671936D02*
Y-665636D01*
G01X-33012D02*
Y-671936D01*
G01Y-668786D02*
X-36302D01*
G01X-29297Y-665636D02*
X-27417D01*
G01X-28357D02*
Y-671936D01*
G01X-29297D02*
X-27417D01*
G01X-20490D02*
X-23624D01*
Y-665636D01*
X-20490D01*
G01X-21744Y-668681D02*
X-23624D01*
G01X-17559Y-671936D02*
Y-665636D01*
X-13955Y-671936D01*
Y-665636D01*
G01X-9614Y-673091D02*
X-9300Y-671726D01*
G01X-3157Y-665636D02*
Y-671936D01*
G01X-4959Y-665636D02*
X-1355D01*
G01X1185Y-671936D02*
X3143Y-665636D01*
X5101Y-671936D01*
G01X4396Y-669731D02*
X1890D01*
G01X8503Y-665636D02*
X10383D01*
G01X9443D02*
Y-671936D01*
G01X8503D02*
X10383D01*
G01X13393Y-665636D02*
X14490Y-671936D01*
X15743Y-665636D01*
X16996Y-671936D01*
X18093Y-665636D01*
G01X20085Y-671936D02*
X22043Y-665636D01*
X24001Y-671936D01*
G01X23296Y-669731D02*
X20790D01*
G01X26541Y-671936D02*
Y-665636D01*
X30145Y-671936D01*
Y-665636D01*
G01X39376Y-671936D02*
Y-665636D01*
X41335D01*
X41961Y-665951D01*
X42353Y-666371D01*
X42510Y-667211D01*
X42353Y-668051D01*
X41883Y-668576D01*
X41335Y-668891D01*
X39376D01*
G01X41335D02*
X42510Y-671936D01*
G01X47243Y-672146D02*
X47086Y-672041D01*
Y-671831D01*
X47243Y-671726D01*
X47400Y-671831D01*
Y-672041D01*
X47243Y-672146D01*
G01X53543Y-671936D02*
X52916Y-671831D01*
X52368Y-671411D01*
X51898Y-670781D01*
X51585Y-670046D01*
X51428Y-669206D01*
Y-668366D01*
X51585Y-667526D01*
X51898Y-666791D01*
X52368Y-666161D01*
X52916Y-665741D01*
X53543Y-665636D01*
X54170Y-665741D01*
X54718Y-666161D01*
X55188Y-666791D01*
X55501Y-667526D01*
X55658Y-668366D01*
Y-669206D01*
X55501Y-670046D01*
X55188Y-670781D01*
X54718Y-671411D01*
X54170Y-671831D01*
X53543Y-671936D01*
G01X59843Y-672146D02*
X59686Y-672041D01*
Y-671831D01*
X59843Y-671726D01*
X60000Y-671831D01*
Y-672041D01*
X59843Y-672146D01*
G01X67866Y-666161D02*
X67396Y-665846D01*
X66848Y-665636D01*
X66221D01*
X65516Y-665951D01*
X64968Y-666476D01*
X64576Y-667106D01*
X64263Y-668156D01*
X64185Y-669101D01*
X64341Y-670046D01*
X64576Y-670676D01*
X65046Y-671306D01*
X65595Y-671726D01*
X66143Y-671936D01*
X66691D01*
X67240Y-671726D01*
X67710Y-671411D01*
X68101Y-670991D01*
G01X72443Y-672146D02*
X72286Y-672041D01*
Y-671831D01*
X72443Y-671726D01*
X72600Y-671831D01*
Y-672041D01*
X72443Y-672146D01*
G01X-42680Y-661936D02*
Y-655636D01*
G01X-39704D02*
X-42680Y-659521D01*
G01X-39234Y-661936D02*
X-41349Y-657736D01*
G01X-36380Y-655636D02*
Y-660151D01*
X-36067Y-661096D01*
X-35440Y-661726D01*
X-34657Y-661936D01*
X-33874Y-661726D01*
X-33247Y-661096D01*
X-32934Y-660151D01*
Y-655636D01*
G01X-26790Y-661936D02*
X-29924D01*
Y-655636D01*
X-26790D01*
G01X-28044Y-658681D02*
X-29924D01*
G01X-22997Y-655636D02*
X-21117D01*
G01X-22057D02*
Y-661936D01*
G01X-22997D02*
X-21117D01*
G01X-11102Y-661096D02*
X-10475Y-661621D01*
X-9770Y-661936D01*
X-9144D01*
X-8517Y-661621D01*
X-8047Y-661096D01*
X-7812Y-660361D01*
X-7969Y-659626D01*
X-8360Y-658996D01*
X-9065Y-658576D01*
X-10005Y-658366D01*
X-10554Y-657946D01*
X-10789Y-657211D01*
X-10632Y-656476D01*
X-10240Y-655951D01*
X-9692Y-655636D01*
X-9144D01*
X-8595Y-655846D01*
X-8125Y-656371D01*
G01X-4802Y-661936D02*
Y-655636D01*
G01X-1512D02*
Y-661936D01*
G01Y-658786D02*
X-4802D01*
G01X1185Y-661936D02*
X3143Y-655636D01*
X5101Y-661936D01*
G01X4396Y-659731D02*
X1890D01*
G01X7641Y-661936D02*
Y-655636D01*
X11245Y-661936D01*
Y-655636D01*
G01X20398Y-661936D02*
Y-655636D01*
G01X23688D02*
Y-661936D01*
G01Y-658786D02*
X20398D01*
G01X26698Y-661096D02*
X27325Y-661621D01*
X28030Y-661936D01*
X28656D01*
X29283Y-661621D01*
X29753Y-661096D01*
X29988Y-660361D01*
X29831Y-659626D01*
X29440Y-658996D01*
X28735Y-658576D01*
X27795Y-658366D01*
X27246Y-657946D01*
X27011Y-657211D01*
X27168Y-656476D01*
X27560Y-655951D01*
X28108Y-655636D01*
X28656D01*
X29205Y-655846D01*
X29675Y-656371D01*
G01X33703Y-655636D02*
X35583D01*
G01X34643D02*
Y-661936D01*
G01X33703D02*
X35583D01*
G01X38985D02*
X40943Y-655636D01*
X42901Y-661936D01*
G01X42196Y-659731D02*
X39690D01*
G01X45441Y-661936D02*
Y-655636D01*
X49045Y-661936D01*
Y-655636D01*
G01X54013Y-658786D02*
X55580D01*
Y-660676D01*
X55110Y-661306D01*
X54561Y-661726D01*
X53778Y-661936D01*
X52995Y-661726D01*
X52446Y-661306D01*
X51976Y-660676D01*
X51663Y-659941D01*
X51506Y-659101D01*
Y-658366D01*
X51663Y-657736D01*
X51976Y-657001D01*
X52446Y-656371D01*
X52916Y-655951D01*
X53543Y-655636D01*
X54091D01*
X54718Y-655846D01*
X55188Y-656266D01*
G01X59686Y-663091D02*
X60000Y-661726D01*
G01X66143Y-655636D02*
Y-661936D01*
G01X64341Y-655636D02*
X67945D01*
G01X70485Y-661936D02*
X72443Y-655636D01*
X74401Y-661936D01*
G01X73696Y-659731D02*
X71190D01*
G01X78743Y-661936D02*
X78116Y-661831D01*
X77568Y-661411D01*
X77098Y-660781D01*
X76785Y-660046D01*
X76628Y-659206D01*
Y-658366D01*
X76785Y-657526D01*
X77098Y-656791D01*
X77568Y-656161D01*
X78116Y-655741D01*
X78743Y-655636D01*
X79370Y-655741D01*
X79918Y-656161D01*
X80388Y-656791D01*
X80701Y-657526D01*
X80858Y-658366D01*
Y-659206D01*
X80701Y-660046D01*
X80388Y-660781D01*
X79918Y-661411D01*
X79370Y-661831D01*
X78743Y-661936D01*
G01X91343D02*
Y-659101D01*
X89776Y-655636D01*
G01X92910D02*
X91343Y-659101D01*
G01X95920Y-655636D02*
Y-660151D01*
X96233Y-661096D01*
X96860Y-661726D01*
X97643Y-661936D01*
X98426Y-661726D01*
X99053Y-661096D01*
X99366Y-660151D01*
Y-655636D01*
G01X101985Y-661936D02*
X103943Y-655636D01*
X105901Y-661936D01*
G01X105196Y-659731D02*
X102690D01*
G01X108441Y-661936D02*
Y-655636D01*
X112045Y-661936D01*
Y-655636D01*
G01X-42759Y-651936D02*
Y-645636D01*
X-39155Y-651936D01*
Y-645636D01*
G01X-34657Y-651936D02*
X-35284Y-651831D01*
X-35832Y-651411D01*
X-36302Y-650781D01*
X-36615Y-650046D01*
X-36772Y-649206D01*
Y-648366D01*
X-36615Y-647526D01*
X-36302Y-646791D01*
X-35832Y-646161D01*
X-35284Y-645741D01*
X-34657Y-645636D01*
X-34030Y-645741D01*
X-33482Y-646161D01*
X-33012Y-646791D01*
X-32699Y-647526D01*
X-32542Y-648366D01*
Y-649206D01*
X-32699Y-650046D01*
X-33012Y-650781D01*
X-33482Y-651411D01*
X-34030Y-651831D01*
X-34657Y-651936D01*
G01X-28357Y-652146D02*
X-28514Y-652041D01*
Y-651831D01*
X-28357Y-651726D01*
X-28200Y-651831D01*
Y-652041D01*
X-28357Y-652146D01*
G01X-22057Y-651936D02*
Y-645636D01*
X-22997Y-646896D01*
G01Y-651936D02*
X-21117D01*
G01X-15757D02*
X-15209Y-651831D01*
X-14582Y-651516D01*
X-14190Y-650991D01*
X-14034Y-650256D01*
X-14190Y-649521D01*
X-14660Y-648891D01*
X-15365Y-648576D01*
X-16149D01*
X-16619Y-648366D01*
X-17010Y-647841D01*
X-17167Y-647106D01*
X-16932Y-646371D01*
X-16384Y-645846D01*
X-15757Y-645636D01*
X-15130Y-645846D01*
X-14582Y-646371D01*
X-14347Y-647106D01*
X-14504Y-647841D01*
X-14895Y-648366D01*
X-15365Y-648576D01*
X-16149D01*
X-16854Y-648891D01*
X-17324Y-649521D01*
X-17480Y-650256D01*
X-17324Y-650991D01*
X-16932Y-651516D01*
X-16305Y-651831D01*
X-15757Y-651936D01*
G01X-9457D02*
X-8909Y-651831D01*
X-8282Y-651516D01*
X-7890Y-650991D01*
X-7734Y-650256D01*
X-7890Y-649521D01*
X-8360Y-648891D01*
X-9065Y-648576D01*
X-9849D01*
X-10319Y-648366D01*
X-10710Y-647841D01*
X-10867Y-647106D01*
X-10632Y-646371D01*
X-10084Y-645846D01*
X-9457Y-645636D01*
X-8830Y-645846D01*
X-8282Y-646371D01*
X-8047Y-647106D01*
X-8204Y-647841D01*
X-8595Y-648366D01*
X-9065Y-648576D01*
X-9849D01*
X-10554Y-648891D01*
X-11024Y-649521D01*
X-11180Y-650256D01*
X-11024Y-650991D01*
X-10632Y-651516D01*
X-10005Y-651831D01*
X-9457Y-651936D01*
G01X-3314Y-653091D02*
X-3000Y-651726D01*
G01X793Y-645636D02*
X1890Y-651936D01*
X3143Y-645636D01*
X4396Y-651936D01*
X5493Y-645636D01*
G01X11010Y-651936D02*
X7876D01*
Y-645636D01*
X11010D01*
G01X9756Y-648681D02*
X7876D01*
G01X13941Y-651936D02*
Y-645636D01*
X17545Y-651936D01*
Y-645636D01*
G01X26698Y-651936D02*
Y-645636D01*
G01X29988D02*
Y-651936D01*
G01Y-648786D02*
X26698D01*
G01X32293Y-645636D02*
X33390Y-651936D01*
X34643Y-645636D01*
X35896Y-651936D01*
X36993Y-645636D01*
G01X38985Y-651936D02*
X40943Y-645636D01*
X42901Y-651936D01*
G01X42196Y-649731D02*
X39690D01*
G01X52055Y-646686D02*
X52525Y-646056D01*
X53073Y-645741D01*
X53700Y-645636D01*
X54483Y-645846D01*
X55031Y-646371D01*
X55188Y-647001D01*
X55110Y-647631D01*
X54796Y-648156D01*
X53230Y-649206D01*
X52525Y-649941D01*
X52055Y-650991D01*
X51898Y-651936D01*
X55188D01*
G01X58041D02*
Y-645636D01*
X61645Y-651936D01*
Y-645636D01*
G01X64420Y-651936D02*
Y-645636D01*
X65986D01*
X66613Y-645951D01*
X67083Y-646371D01*
X67475Y-647001D01*
X67788Y-647736D01*
X67866Y-648786D01*
X67788Y-649836D01*
X67475Y-650571D01*
X67083Y-651201D01*
X66613Y-651621D01*
X65986Y-651936D01*
X64420D01*
G01X77176D02*
Y-645636D01*
X79135D01*
X79761Y-645951D01*
X80153Y-646371D01*
X80310Y-647211D01*
X80153Y-648051D01*
X79683Y-648576D01*
X79135Y-648891D01*
X77176D01*
G01X79135D02*
X80310Y-651936D01*
G01X83320D02*
Y-645636D01*
X84886D01*
X85513Y-645951D01*
X85983Y-646371D01*
X86375Y-647001D01*
X86688Y-647736D01*
X86766Y-648786D01*
X86688Y-649836D01*
X86375Y-650571D01*
X85983Y-651201D01*
X85513Y-651621D01*
X84886Y-651936D01*
X83320D01*
G01X91343Y-652146D02*
X91186Y-652041D01*
Y-651831D01*
X91343Y-651726D01*
X91500Y-651831D01*
Y-652041D01*
X91343Y-652146D01*
G01X-33604Y-48682D02*
Y-53362D01*
G01Y-51022D02*
X-49204D01*
G01Y-48682D02*
Y-53362D01*
G01X-47124Y-64827D02*
X-48424Y-66387D01*
X-49204Y-68142D01*
Y-69702D01*
X-48424Y-71262D01*
X-47124Y-72432D01*
X-45304Y-73017D01*
X-43484Y-72627D01*
X-41924Y-71652D01*
X-40884Y-69897D01*
X-40364Y-67557D01*
X-39324Y-66192D01*
X-37504Y-65607D01*
X-35684Y-65997D01*
X-34384Y-66972D01*
X-33604Y-68337D01*
Y-69702D01*
X-34124Y-71067D01*
X-35424Y-72237D01*
G01X-33604Y-86822D02*
X-49204D01*
G01X-33604Y-82337D02*
Y-91307D01*
G01X-41404Y-123792D02*
Y-127692D01*
X-46084D01*
X-47644Y-126522D01*
X-48684Y-125157D01*
X-49204Y-123207D01*
X-48684Y-121257D01*
X-47644Y-119892D01*
X-46084Y-118722D01*
X-44264Y-117942D01*
X-42184Y-117552D01*
X-40364D01*
X-38804Y-117942D01*
X-36984Y-118722D01*
X-35424Y-119892D01*
X-34384Y-121062D01*
X-33604Y-122622D01*
Y-123987D01*
X-34124Y-125547D01*
X-35164Y-126717D01*
G01X-49204Y-144422D02*
Y-136622D01*
X-33604D01*
Y-144422D01*
G01X-41144Y-141302D02*
Y-136622D01*
G01X-49204Y-154522D02*
X-33604D01*
Y-159397D01*
X-34384Y-160957D01*
X-35424Y-161932D01*
X-37504Y-162322D01*
X-39584Y-161932D01*
X-40884Y-160762D01*
X-41664Y-159397D01*
Y-154522D01*
G01Y-159397D02*
X-49204Y-162322D01*
G01X-40884Y-177882D02*
X-40104Y-178662D01*
X-38804Y-179247D01*
X-36984Y-179637D01*
X-35424Y-179247D01*
X-34384Y-178467D01*
X-33604Y-177102D01*
Y-171837D01*
X-49204D01*
Y-178272D01*
X-48164Y-179637D01*
X-46604Y-180417D01*
X-44784Y-180807D01*
X-42964Y-180417D01*
X-41404Y-179247D01*
X-40884Y-177882D01*
Y-171837D01*
G01X-49204Y-198122D02*
Y-190322D01*
X-33604D01*
Y-198122D01*
G01X-41144Y-195002D02*
Y-190322D01*
G01X-49204Y-208222D02*
X-33604D01*
Y-213097D01*
X-34384Y-214657D01*
X-35424Y-215632D01*
X-37504Y-216022D01*
X-39584Y-215632D01*
X-40884Y-214462D01*
X-41664Y-213097D01*
Y-208222D01*
G01Y-213097D02*
X-49204Y-216022D01*
G01X-54404Y-229047D02*
X-51804Y-227097D01*
X-49204Y-226122D01*
X-38804D01*
X-36204Y-227097D01*
X-33604Y-229047D01*
G01Y-247922D02*
X-49204D01*
G01X-33604Y-243437D02*
Y-252407D01*
G01Y-260947D02*
X-49204Y-265822D01*
X-33604Y-270697D01*
G01X-49204Y-279627D02*
X-33604Y-287817D01*
G01Y-279627D02*
X-49204Y-287817D01*
G01Y-301622D02*
X-33604D01*
X-36724Y-299282D01*
G01X-49204D02*
Y-303962D01*
G01X-36204Y-315817D02*
X-34644Y-316987D01*
X-33864Y-318352D01*
X-33604Y-319912D01*
X-34124Y-321862D01*
X-35424Y-323227D01*
X-36984Y-323617D01*
X-38544Y-323422D01*
X-39844Y-322642D01*
X-42444Y-318742D01*
X-44264Y-316987D01*
X-46864Y-315817D01*
X-49204Y-315427D01*
Y-323617D01*
G01X-46864Y-333132D02*
X-48164Y-334302D01*
X-48944Y-335667D01*
X-49204Y-337422D01*
X-48684Y-339177D01*
X-47644Y-340542D01*
X-45824Y-341517D01*
X-43744Y-341712D01*
X-41664Y-341322D01*
X-40364Y-340347D01*
X-39324Y-338982D01*
X-39064Y-337617D01*
X-39324Y-336252D01*
X-40364Y-334497D01*
X-33604Y-335082D01*
Y-340347D01*
G01X-46864Y-351032D02*
X-48164Y-352202D01*
X-48944Y-353567D01*
X-49204Y-355322D01*
X-48684Y-357077D01*
X-47644Y-358442D01*
X-45824Y-359417D01*
X-43744Y-359612D01*
X-41664Y-359222D01*
X-40364Y-358247D01*
X-39324Y-356882D01*
X-39064Y-355517D01*
X-39324Y-354152D01*
X-40364Y-352397D01*
X-33604Y-352982D01*
Y-358247D01*
G01X-42704Y-369517D02*
X-40884Y-370882D01*
X-39844Y-372052D01*
X-39324Y-373612D01*
X-39844Y-374977D01*
X-40884Y-375952D01*
X-42444Y-376732D01*
X-44264Y-376927D01*
X-45824Y-376732D01*
X-47384Y-375952D01*
X-48684Y-374782D01*
X-49204Y-373417D01*
X-48684Y-371857D01*
X-47124Y-370492D01*
X-44784Y-369712D01*
X-42184Y-369517D01*
X-38804Y-369907D01*
X-36984Y-370492D01*
X-35164Y-371467D01*
X-33864Y-372832D01*
X-33604Y-374197D01*
X-34124Y-375562D01*
X-35424Y-376537D01*
G01X-40884Y-392682D02*
X-40104Y-393462D01*
X-38804Y-394047D01*
X-36984Y-394437D01*
X-35424Y-394047D01*
X-34384Y-393267D01*
X-33604Y-391902D01*
Y-386637D01*
X-49204D01*
Y-393072D01*
X-48164Y-394437D01*
X-46604Y-395217D01*
X-44784Y-395607D01*
X-42964Y-395217D01*
X-41404Y-394047D01*
X-40884Y-392682D01*
Y-386637D01*
G01X-54404Y-409997D02*
X-51804Y-411947D01*
X-49204Y-412922D01*
X-38804D01*
X-36204Y-411947D01*
X-33604Y-409997D01*
G01X-18657Y-639236D02*
X-21177Y-638819D01*
X-23382Y-637153D01*
X-25272Y-634653D01*
X-26532Y-631736D01*
X-27162Y-628403D01*
Y-625069D01*
X-26532Y-621736D01*
X-25272Y-618819D01*
X-23382Y-616320D01*
X-21177Y-614653D01*
X-18657Y-614236D01*
X-16137Y-614653D01*
X-13932Y-616320D01*
X-12042Y-618819D01*
X-10782Y-621736D01*
X-10152Y-625069D01*
Y-628403D01*
X-10782Y-631736D01*
X-12042Y-634653D01*
X-13932Y-637153D01*
X-16137Y-638819D01*
X-18657Y-639236D01*
G01X-16137Y-632569D02*
X-12357Y-639236D01*
G01X1188Y-622570D02*
Y-634236D01*
X2448Y-637153D01*
X4338Y-638819D01*
X6543Y-639236D01*
X8748Y-638819D01*
X10638Y-637153D01*
X11898Y-634236D01*
G01Y-639236D02*
Y-622570D01*
G01X37413Y-639236D02*
Y-622570D01*
G01Y-625486D02*
X36153Y-623820D01*
X34263Y-622986D01*
X32058Y-622570D01*
X29853Y-623403D01*
X27963Y-625069D01*
X26703Y-627570D01*
X26073Y-630903D01*
X26703Y-634236D01*
X27963Y-636737D01*
X29853Y-638403D01*
X32058Y-639236D01*
X34263Y-638819D01*
X36153Y-637570D01*
X37413Y-635903D01*
G01X51588Y-639236D02*
Y-622570D01*
G01Y-626736D02*
X52848Y-624653D01*
X54738Y-622986D01*
X57258Y-622570D01*
X59463Y-622986D01*
X61353Y-624653D01*
X62298Y-627570D01*
Y-639236D01*
G01X82143Y-614236D02*
Y-639236D01*
G01X77733Y-622570D02*
X86553D01*
G01X113013Y-639236D02*
Y-622570D01*
G01Y-625486D02*
X111753Y-623820D01*
X109863Y-622986D01*
X107658Y-622570D01*
X105453Y-623403D01*
X103563Y-625069D01*
X102303Y-627570D01*
X101673Y-630903D01*
X102303Y-634236D01*
X103563Y-636737D01*
X105453Y-638403D01*
X107658Y-639236D01*
X109863Y-638819D01*
X111753Y-637570D01*
X113013Y-635903D01*
G01X123337Y-368560D02*
X225811D01*
Y-169897D01*
G01X230994Y342901D02*
X128520D01*
Y144238D01*
G01X128619Y263275D02*
X202587D01*
G01X152693Y-618936D02*
Y-626936D01*
X156693D01*
G01X164493D02*
Y-621603D01*
G01Y-622536D02*
X164093Y-622003D01*
X163493Y-621736D01*
X162793Y-621603D01*
X162093Y-621869D01*
X161493Y-622403D01*
X161093Y-623203D01*
X160893Y-624269D01*
X161093Y-625336D01*
X161493Y-626136D01*
X162093Y-626669D01*
X162793Y-626936D01*
X163493Y-626803D01*
X164093Y-626403D01*
X164493Y-625870D01*
G01X168593Y-629336D02*
X169193Y-629603D01*
X169993Y-629336D01*
X170493Y-628803D01*
X170893Y-628136D01*
X171493Y-626003D01*
X172793Y-621603D01*
G01X169593D02*
X171493Y-626003D01*
G01X177193Y-623336D02*
X180393D01*
X180093Y-622403D01*
X179593Y-621869D01*
X178893Y-621603D01*
X178193Y-621736D01*
X177593Y-622136D01*
X177193Y-623069D01*
X176993Y-623870D01*
Y-624669D01*
X177193Y-625469D01*
X177693Y-626269D01*
X178293Y-626803D01*
X178993Y-626936D01*
X179693Y-626669D01*
X180393Y-625870D01*
G01X185293Y-626936D02*
Y-621603D01*
G01Y-622669D02*
X185793Y-622136D01*
X186293Y-621736D01*
X186993Y-621603D01*
X187493Y-621736D01*
X188093Y-622136D01*
G01X225712Y-288934D02*
X151744D01*
G01X162429Y522141D02*
X163359Y521099D01*
X164444Y520474D01*
X165839Y520266D01*
X167234Y520683D01*
X168319Y521516D01*
X169094Y522974D01*
X169249Y524641D01*
X168939Y526308D01*
X168164Y527349D01*
X167079Y528183D01*
X165994Y528391D01*
X164909Y528183D01*
X163514Y527349D01*
X163979Y532766D01*
X168164D01*
G01X175294Y525474D02*
X176379Y526933D01*
X177309Y527766D01*
X178549Y528183D01*
X179634Y527766D01*
X180409Y526933D01*
X181029Y525683D01*
X181184Y524224D01*
X181029Y522974D01*
X180409Y521724D01*
X179479Y520683D01*
X178394Y520266D01*
X177154Y520683D01*
X176069Y521932D01*
X175449Y523808D01*
X175294Y525891D01*
X175604Y528599D01*
X176069Y530058D01*
X176844Y531516D01*
X177929Y532558D01*
X179014Y532766D01*
X180099Y532349D01*
X180874Y531308D01*
G01X187694Y530683D02*
X188624Y531932D01*
X189709Y532558D01*
X190949Y532766D01*
X192499Y532349D01*
X193584Y531308D01*
X193894Y530058D01*
X193739Y528807D01*
X193119Y527766D01*
X190019Y525683D01*
X188624Y524224D01*
X187694Y522141D01*
X187384Y520266D01*
X193894D01*
G01X203039D02*
Y532766D01*
X201179Y530266D01*
G01Y520266D02*
X204899D01*
G01X215439Y519849D02*
X215129Y520058D01*
Y520474D01*
X215439Y520683D01*
X215749Y520474D01*
Y520058D01*
X215439Y519849D01*
G01X224894Y530683D02*
X225824Y531932D01*
X226909Y532558D01*
X228149Y532766D01*
X229699Y532349D01*
X230784Y531308D01*
X231094Y530058D01*
X230939Y528807D01*
X230319Y527766D01*
X227219Y525683D01*
X225824Y524224D01*
X224894Y522141D01*
X224584Y520266D01*
X231094D01*
G01X237294Y525474D02*
X238379Y526933D01*
X239309Y527766D01*
X240549Y528183D01*
X241634Y527766D01*
X242409Y526933D01*
X243029Y525683D01*
X243184Y524224D01*
X243029Y522974D01*
X242409Y521724D01*
X241479Y520683D01*
X240394Y520266D01*
X239154Y520683D01*
X238069Y521932D01*
X237449Y523808D01*
X237294Y525891D01*
X237604Y528599D01*
X238069Y530058D01*
X238844Y531516D01*
X239929Y532558D01*
X241014Y532766D01*
X242099Y532349D01*
X242874Y531308D01*
G01X173993Y-676936D02*
Y-668936D01*
G01X177793D02*
X173993Y-673870D01*
G01X178393Y-676936D02*
X175693Y-671603D01*
G01X185993Y-676936D02*
Y-671603D01*
G01Y-672536D02*
X185593Y-672003D01*
X184993Y-671736D01*
X184293Y-671603D01*
X183593Y-671869D01*
X182993Y-672403D01*
X182593Y-673203D01*
X182393Y-674269D01*
X182593Y-675336D01*
X182993Y-676136D01*
X183593Y-676669D01*
X184293Y-676936D01*
X184993Y-676803D01*
X185593Y-676403D01*
X185993Y-675870D01*
G01X192193Y-671603D02*
Y-676936D01*
G01Y-669469D02*
X191993Y-669336D01*
Y-669069D01*
X192193Y-668936D01*
X192393Y-669069D01*
Y-669336D01*
X192193Y-669469D01*
G01X171693Y-651936D02*
Y-643936D01*
X174093D01*
X174893Y-644336D01*
X175493Y-645269D01*
X175693Y-646336D01*
X175493Y-647403D01*
X174993Y-648203D01*
X174093Y-648603D01*
X171693D01*
G01X179193Y-651936D02*
X181693Y-643936D01*
X184193Y-651936D01*
G01X183293Y-649136D02*
X180093D01*
G01X187393Y-651936D02*
Y-643936D01*
X191993Y-651936D01*
Y-643936D01*
G01X199693Y-651936D02*
X195693D01*
Y-643936D01*
X199693D01*
G01X198093Y-647803D02*
X195693D01*
G01X203693Y-643936D02*
Y-651936D01*
X207693D01*
G01X172189Y495266D02*
Y507766D01*
X170329Y505266D01*
G01Y495266D02*
X174049D01*
G01X186449D02*
Y507766D01*
X180714Y498808D01*
X188464D01*
G01X194044Y505683D02*
X194974Y506932D01*
X196059Y507558D01*
X197299Y507766D01*
X198849Y507349D01*
X199934Y506308D01*
X200244Y505058D01*
X200089Y503807D01*
X199469Y502766D01*
X196369Y500683D01*
X194974Y499224D01*
X194044Y497141D01*
X193734Y495266D01*
X200244D01*
G01X209389Y494849D02*
X209079Y495058D01*
Y495474D01*
X209389Y495683D01*
X209699Y495474D01*
Y495058D01*
X209389Y494849D01*
G01X221479Y495266D02*
X221789Y497974D01*
X222254Y500266D01*
X222874Y502349D01*
X223649Y504641D01*
X224889Y507766D01*
X218689D01*
G01X234189Y495266D02*
X235274Y495474D01*
X236514Y496099D01*
X237289Y497141D01*
X237599Y498599D01*
X237289Y500057D01*
X236359Y501308D01*
X234964Y501933D01*
X233414D01*
X232484Y502349D01*
X231709Y503391D01*
X231399Y504849D01*
X231864Y506308D01*
X232949Y507349D01*
X234189Y507766D01*
X235429Y507349D01*
X236514Y506308D01*
X236979Y504849D01*
X236669Y503391D01*
X235894Y502349D01*
X234964Y501933D01*
X233414D01*
X232019Y501308D01*
X231089Y500057D01*
X230779Y498599D01*
X231089Y497141D01*
X231864Y496099D01*
X233104Y495474D01*
X234189Y495266D01*
G01X279293Y-670269D02*
X279893Y-669469D01*
X280593Y-669069D01*
X281393Y-668936D01*
X282393Y-669203D01*
X283093Y-669869D01*
X283293Y-670669D01*
X283193Y-671470D01*
X282793Y-672136D01*
X280793Y-673469D01*
X279893Y-674403D01*
X279293Y-675736D01*
X279093Y-676936D01*
X283293D01*
G01X289193Y-668936D02*
X288393Y-669203D01*
X287793Y-669869D01*
X287393Y-670669D01*
X287093Y-671736D01*
X286993Y-672936D01*
X287093Y-674136D01*
X287393Y-675203D01*
X287793Y-676003D01*
X288393Y-676669D01*
X289193Y-676936D01*
X289993Y-676669D01*
X290593Y-676003D01*
X290993Y-675203D01*
X291293Y-674136D01*
X291393Y-672936D01*
X291293Y-671736D01*
X290993Y-670669D01*
X290593Y-669869D01*
X289993Y-669203D01*
X289193Y-668936D01*
G01X295293Y-670269D02*
X295893Y-669469D01*
X296593Y-669069D01*
X297393Y-668936D01*
X298393Y-669203D01*
X299093Y-669869D01*
X299293Y-670669D01*
X299193Y-671470D01*
X298793Y-672136D01*
X296793Y-673469D01*
X295893Y-674403D01*
X295293Y-675736D01*
X295093Y-676936D01*
X299293D01*
G01X303293Y-670269D02*
X303893Y-669469D01*
X304593Y-669069D01*
X305393Y-668936D01*
X306393Y-669203D01*
X307093Y-669869D01*
X307293Y-670669D01*
X307193Y-671470D01*
X306793Y-672136D01*
X304793Y-673469D01*
X303893Y-674403D01*
X303293Y-675736D01*
X303093Y-676936D01*
X307293D01*
G01X311393Y-677203D02*
X314993Y-668936D01*
G01X321193Y-676936D02*
Y-668936D01*
X319993Y-670536D01*
G01Y-676936D02*
X322393D01*
G01X327293Y-670269D02*
X327893Y-669469D01*
X328593Y-669069D01*
X329393Y-668936D01*
X330393Y-669203D01*
X331093Y-669869D01*
X331293Y-670669D01*
X331193Y-671470D01*
X330793Y-672136D01*
X328793Y-673469D01*
X327893Y-674403D01*
X327293Y-675736D01*
X327093Y-676936D01*
X331293D01*
G01X335393Y-677203D02*
X338993Y-668936D01*
G01X345193D02*
X344393Y-669203D01*
X343793Y-669869D01*
X343393Y-670669D01*
X343093Y-671736D01*
X342993Y-672936D01*
X343093Y-674136D01*
X343393Y-675203D01*
X343793Y-676003D01*
X344393Y-676669D01*
X345193Y-676936D01*
X345993Y-676669D01*
X346593Y-676003D01*
X346993Y-675203D01*
X347293Y-674136D01*
X347393Y-672936D01*
X347293Y-671736D01*
X346993Y-670669D01*
X346593Y-669869D01*
X345993Y-669203D01*
X345193Y-668936D01*
G01X351493Y-676003D02*
X352193Y-676669D01*
X352993Y-676936D01*
X353793Y-676669D01*
X354493Y-675870D01*
X354993Y-674669D01*
X355193Y-673469D01*
Y-672003D01*
X354993Y-670803D01*
X354493Y-669736D01*
X353893Y-669203D01*
X353193Y-668936D01*
X352393Y-669203D01*
X351793Y-669736D01*
X351393Y-670536D01*
X351193Y-671603D01*
X351393Y-672536D01*
X351893Y-673469D01*
X352493Y-674003D01*
X353193Y-674136D01*
X353993Y-673870D01*
X354593Y-673203D01*
X355193Y-672003D01*
G01X278993Y-651936D02*
Y-643936D01*
X280993D01*
X281793Y-644336D01*
X282393Y-644869D01*
X282893Y-645669D01*
X283293Y-646603D01*
X283393Y-647936D01*
X283293Y-649269D01*
X282893Y-650203D01*
X282393Y-651003D01*
X281793Y-651536D01*
X280993Y-651936D01*
X278993D01*
G01X286693D02*
X289193Y-643936D01*
X291693Y-651936D01*
G01X290793Y-649136D02*
X287593D01*
G01X297193Y-643936D02*
X296393Y-644203D01*
X295793Y-644869D01*
X295393Y-645669D01*
X295093Y-646736D01*
X294993Y-647936D01*
X295093Y-649136D01*
X295393Y-650203D01*
X295793Y-651003D01*
X296393Y-651669D01*
X297193Y-651936D01*
X297993Y-651669D01*
X298593Y-651003D01*
X298993Y-650203D01*
X299293Y-649136D01*
X299393Y-647936D01*
X299293Y-646736D01*
X298993Y-645669D01*
X298593Y-644869D01*
X297993Y-644203D01*
X297193Y-643936D01*
G01X303293Y-651936D02*
Y-643936D01*
X307093D01*
G01X305693Y-647803D02*
X303293D01*
G01X313193Y-643936D02*
X312393Y-644203D01*
X311793Y-644869D01*
X311393Y-645669D01*
X311093Y-646736D01*
X310993Y-647936D01*
X311093Y-649136D01*
X311393Y-650203D01*
X311793Y-651003D01*
X312393Y-651669D01*
X313193Y-651936D01*
X313993Y-651669D01*
X314593Y-651003D01*
X314993Y-650203D01*
X315293Y-649136D01*
X315393Y-647936D01*
X315293Y-646736D01*
X314993Y-645669D01*
X314593Y-644869D01*
X313993Y-644203D01*
X313193Y-643936D01*
G01X321193D02*
Y-651936D01*
G01X318893Y-643936D02*
X323493D01*
G01X326593Y-651936D02*
Y-643936D01*
X329193Y-650603D01*
X331793Y-643936D01*
Y-651936D01*
G01X334993D02*
Y-643936D01*
X336993D01*
X337793Y-644336D01*
X338393Y-644869D01*
X338893Y-645669D01*
X339293Y-646603D01*
X339393Y-647936D01*
X339293Y-649269D01*
X338893Y-650203D01*
X338393Y-651003D01*
X337793Y-651536D01*
X336993Y-651936D01*
X334993D01*
G01X347393Y-644603D02*
X346793Y-644203D01*
X346093Y-643936D01*
X345293D01*
X344393Y-644336D01*
X343693Y-645003D01*
X343193Y-645803D01*
X342793Y-647136D01*
X342693Y-648336D01*
X342893Y-649536D01*
X343193Y-650336D01*
X343793Y-651136D01*
X344493Y-651669D01*
X345193Y-651936D01*
X345893D01*
X346593Y-651669D01*
X347193Y-651269D01*
X347693Y-650736D01*
G01X350993Y-651936D02*
Y-643936D01*
X352993D01*
X353793Y-644336D01*
X354393Y-644869D01*
X354893Y-645669D01*
X355293Y-646603D01*
X355393Y-647936D01*
X355293Y-649269D01*
X354893Y-650203D01*
X354393Y-651003D01*
X353793Y-651536D01*
X352993Y-651936D01*
X350993D01*
G01X361193Y-643936D02*
X360393Y-644203D01*
X359793Y-644869D01*
X359393Y-645669D01*
X359093Y-646736D01*
X358993Y-647936D01*
X359093Y-649136D01*
X359393Y-650203D01*
X359793Y-651003D01*
X360393Y-651669D01*
X361193Y-651936D01*
X361993Y-651669D01*
X362593Y-651003D01*
X362993Y-650203D01*
X363293Y-649136D01*
X363393Y-647936D01*
X363293Y-646736D01*
X362993Y-645669D01*
X362593Y-644869D01*
X361993Y-644203D01*
X361193Y-643936D01*
G01X298418Y-624819D02*
Y-618519D01*
X301394D01*
G01X300298Y-621564D02*
X298418D01*
G01X306206Y-618519D02*
X305579Y-618729D01*
X305109Y-619254D01*
X304796Y-619884D01*
X304561Y-620724D01*
X304483Y-621669D01*
X304561Y-622614D01*
X304796Y-623454D01*
X305109Y-624084D01*
X305579Y-624609D01*
X306206Y-624819D01*
X306833Y-624609D01*
X307303Y-624084D01*
X307616Y-623454D01*
X307851Y-622614D01*
X307929Y-621669D01*
X307851Y-620724D01*
X307616Y-619884D01*
X307303Y-619254D01*
X306833Y-618729D01*
X306206Y-618519D01*
G01X312506D02*
Y-624819D01*
G01X310704Y-618519D02*
X314308D01*
G01X316456Y-626919D02*
X321156D01*
G01X323069Y-624819D02*
Y-618519D01*
X325106Y-623769D01*
X327143Y-618519D01*
Y-624819D01*
G01X332816D02*
Y-620619D01*
G01Y-621354D02*
X332503Y-620934D01*
X332033Y-620724D01*
X331484Y-620619D01*
X330936Y-620829D01*
X330466Y-621249D01*
X330153Y-621879D01*
X329996Y-622719D01*
X330153Y-623559D01*
X330466Y-624189D01*
X330936Y-624609D01*
X331484Y-624819D01*
X332033Y-624714D01*
X332503Y-624399D01*
X332816Y-623979D01*
G01X336374Y-624819D02*
Y-620619D01*
G01Y-621669D02*
X336688Y-621144D01*
X337158Y-620724D01*
X337784Y-620619D01*
X338333Y-620724D01*
X338803Y-621144D01*
X339038Y-621879D01*
Y-624819D01*
G01X345416D02*
Y-620619D01*
G01Y-621354D02*
X345103Y-620934D01*
X344633Y-620724D01*
X344084Y-620619D01*
X343536Y-620829D01*
X343066Y-621249D01*
X342753Y-621879D01*
X342596Y-622719D01*
X342753Y-623559D01*
X343066Y-624189D01*
X343536Y-624609D01*
X344084Y-624819D01*
X344633Y-624714D01*
X345103Y-624399D01*
X345416Y-623979D01*
G01X349209Y-626394D02*
X349758Y-626814D01*
X350384Y-626919D01*
X350933Y-626814D01*
X351403Y-626289D01*
X351716Y-625554D01*
Y-620619D01*
G01Y-621459D02*
X351403Y-621039D01*
X350933Y-620724D01*
X350384Y-620619D01*
X349758Y-620829D01*
X349366Y-621249D01*
X349053Y-621984D01*
X348896Y-622719D01*
X348974Y-623349D01*
X349288Y-624084D01*
X349758Y-624609D01*
X350384Y-624819D01*
X350854Y-624714D01*
X351403Y-624294D01*
X351716Y-623874D01*
G01X355431Y-621984D02*
X357938D01*
X357703Y-621249D01*
X357311Y-620829D01*
X356763Y-620619D01*
X356214Y-620724D01*
X355744Y-621039D01*
X355431Y-621774D01*
X355274Y-622404D01*
Y-623034D01*
X355431Y-623664D01*
X355823Y-624294D01*
X356293Y-624714D01*
X356841Y-624819D01*
X357389Y-624609D01*
X357938Y-623979D01*
G01X360556Y-624819D02*
Y-620619D01*
G01Y-621774D02*
X360791Y-621249D01*
X361183Y-620829D01*
X361731Y-620619D01*
X362279Y-620829D01*
X362671Y-621249D01*
X362906Y-621774D01*
Y-624819D01*
G01Y-621774D02*
X363141Y-621249D01*
X363533Y-620829D01*
X364081Y-620619D01*
X364629Y-620829D01*
X365021Y-621249D01*
X365256Y-621879D01*
Y-624819D01*
G01X368031Y-621984D02*
X370538D01*
X370303Y-621249D01*
X369911Y-620829D01*
X369363Y-620619D01*
X368814Y-620724D01*
X368344Y-621039D01*
X368031Y-621774D01*
X367874Y-622404D01*
Y-623034D01*
X368031Y-623664D01*
X368423Y-624294D01*
X368893Y-624714D01*
X369441Y-624819D01*
X369989Y-624609D01*
X370538Y-623979D01*
G01X374174Y-624819D02*
Y-620619D01*
G01Y-621669D02*
X374488Y-621144D01*
X374958Y-620724D01*
X375584Y-620619D01*
X376133Y-620724D01*
X376603Y-621144D01*
X376838Y-621879D01*
Y-624819D01*
G01X381806Y-618519D02*
Y-624819D01*
G01X380709Y-620619D02*
X382903D01*
G01X385756Y-626919D02*
X390456D01*
G01X395033Y-621459D02*
X395346Y-621144D01*
X395581Y-620619D01*
X395738Y-619884D01*
X395581Y-619254D01*
X395268Y-618834D01*
X394719Y-618519D01*
X392604D01*
Y-624819D01*
X395189D01*
X395738Y-624399D01*
X396051Y-623769D01*
X396208Y-623034D01*
X396051Y-622299D01*
X395581Y-621669D01*
X395033Y-621459D01*
X392604D01*
G01X398983Y-624819D02*
Y-618519D01*
X400549D01*
X401176Y-618834D01*
X401646Y-619254D01*
X402038Y-619884D01*
X402351Y-620619D01*
X402429Y-621669D01*
X402351Y-622719D01*
X402038Y-623454D01*
X401646Y-624084D01*
X401176Y-624504D01*
X400549Y-624819D01*
X398983D01*
G01X367693Y-679936D02*
Y-671936D01*
X366493Y-673536D01*
G01Y-679936D02*
X368893D01*
G01X373793Y-676603D02*
X374493Y-675669D01*
X375093Y-675136D01*
X375893Y-674869D01*
X376593Y-675136D01*
X377093Y-675669D01*
X377493Y-676469D01*
X377593Y-677403D01*
X377493Y-678203D01*
X377093Y-679003D01*
X376493Y-679669D01*
X375793Y-679936D01*
X374993Y-679669D01*
X374293Y-678870D01*
X373893Y-677669D01*
X373793Y-676336D01*
X373993Y-674603D01*
X374293Y-673669D01*
X374793Y-672736D01*
X375493Y-672069D01*
X376193Y-671936D01*
X376893Y-672203D01*
X377393Y-672869D01*
G01X383693Y-680203D02*
X383493Y-680069D01*
Y-679803D01*
X383693Y-679669D01*
X383893Y-679803D01*
Y-680069D01*
X383693Y-680203D01*
G01X389793Y-676603D02*
X390493Y-675669D01*
X391093Y-675136D01*
X391893Y-674869D01*
X392593Y-675136D01*
X393093Y-675669D01*
X393493Y-676469D01*
X393593Y-677403D01*
X393493Y-678203D01*
X393093Y-679003D01*
X392493Y-679669D01*
X391793Y-679936D01*
X390993Y-679669D01*
X390293Y-678870D01*
X389893Y-677669D01*
X389793Y-676336D01*
X389993Y-674603D01*
X390293Y-673669D01*
X390793Y-672736D01*
X391493Y-672069D01*
X392193Y-671936D01*
X392893Y-672203D01*
X393393Y-672869D01*
G01X412693Y-679936D02*
Y-671936D01*
X411493Y-673536D01*
G01Y-679936D02*
X413893D01*
G01X420493D02*
X420693Y-678203D01*
X420993Y-676736D01*
X421393Y-675403D01*
X421893Y-673936D01*
X422693Y-671936D01*
X418693D01*
G01X428693Y-680203D02*
X428493Y-680069D01*
Y-679803D01*
X428693Y-679669D01*
X428893Y-679803D01*
Y-680069D01*
X428693Y-680203D01*
G01X434793Y-673269D02*
X435393Y-672469D01*
X436093Y-672069D01*
X436893Y-671936D01*
X437893Y-672203D01*
X438593Y-672869D01*
X438793Y-673669D01*
X438693Y-674470D01*
X438293Y-675136D01*
X436293Y-676469D01*
X435393Y-677403D01*
X434793Y-678736D01*
X434593Y-679936D01*
X438793D01*
G01X432493Y-654936D02*
Y-646936D01*
X434493D01*
X435293Y-647336D01*
X435893Y-647869D01*
X436393Y-648669D01*
X436793Y-649603D01*
X436893Y-650936D01*
X436793Y-652269D01*
X436393Y-653203D01*
X435893Y-654003D01*
X435293Y-654536D01*
X434493Y-654936D01*
X432493D01*
G01X470817Y-498031D02*
G03I-6250J0D01*
G01X470473Y-450787D02*
G03I-5906J0D01*
G01X470817Y454331D02*
G03I-6250J0D01*
G01X516544Y-61685D02*
X517585Y-60600D01*
X518002Y-59360D01*
X517585Y-58120D01*
X516336Y-57035D01*
X514460Y-56260D01*
X512585Y-55950D01*
X510294D01*
X508419Y-56260D01*
X506752Y-57035D01*
X505919Y-57965D01*
X505502Y-59050D01*
X505919Y-60290D01*
X506752Y-61220D01*
X508002Y-61840D01*
X509669Y-62150D01*
X511127Y-61840D01*
X512585Y-61065D01*
X513419Y-60135D01*
X513627Y-59050D01*
X513211Y-57810D01*
X512169Y-56880D01*
X510294Y-55950D01*
G01X516544Y-49285D02*
X517585Y-48200D01*
X518002Y-46960D01*
X517585Y-45720D01*
X516336Y-44635D01*
X514460Y-43860D01*
X512585Y-43550D01*
X510294D01*
X508419Y-43860D01*
X506752Y-44635D01*
X505919Y-45565D01*
X505502Y-46650D01*
X505919Y-47890D01*
X506752Y-48820D01*
X508002Y-49440D01*
X509669Y-49750D01*
X511127Y-49440D01*
X512585Y-48665D01*
X513419Y-47735D01*
X513627Y-46650D01*
X513211Y-45410D01*
X512169Y-44480D01*
X510294Y-43550D01*
G01X518002Y-34250D02*
X505502D01*
X508002Y-36110D01*
G01X518002D02*
Y-32390D01*
G01Y-22160D02*
X515294Y-21850D01*
X513002Y-21385D01*
X510919Y-20765D01*
X508627Y-19990D01*
X505502Y-18750D01*
Y-24950D01*
G01X518419Y-9450D02*
X518210Y-9760D01*
X517794D01*
X517585Y-9450D01*
X517794Y-9140D01*
X518210D01*
X518419Y-9450D01*
G01X515502Y-460D02*
X516961Y470D01*
X517794Y1710D01*
X518002Y3105D01*
X517794Y4345D01*
X516752Y5585D01*
X515502Y6360D01*
X514252Y6515D01*
X512794Y6205D01*
X511752Y5120D01*
X511335Y4035D01*
Y2640D01*
G01Y4035D02*
X510710Y4965D01*
X509669Y5740D01*
X508419Y6050D01*
X507169Y5740D01*
X506127Y4965D01*
X505502Y3570D01*
X505710Y2175D01*
X506544Y780D01*
G01X507585Y12405D02*
X506336Y13335D01*
X505710Y14420D01*
X505502Y15660D01*
X505919Y17210D01*
X506960Y18295D01*
X508210Y18605D01*
X509461Y18450D01*
X510502Y17830D01*
X512585Y14730D01*
X514044Y13335D01*
X516127Y12405D01*
X518002Y12095D01*
Y18605D01*
G01X532585Y-49445D02*
X531336Y-48515D01*
X530710Y-47430D01*
X530502Y-46190D01*
X530919Y-44640D01*
X531960Y-43555D01*
X533210Y-43245D01*
X534461Y-43400D01*
X535502Y-44020D01*
X537585Y-47120D01*
X539044Y-48515D01*
X541127Y-49445D01*
X543002Y-49755D01*
Y-43245D01*
G01X541127Y-37510D02*
X542169Y-36580D01*
X542794Y-35495D01*
X543002Y-34100D01*
X542585Y-32705D01*
X541752Y-31620D01*
X540294Y-30845D01*
X538627Y-30690D01*
X536960Y-31000D01*
X535919Y-31775D01*
X535085Y-32860D01*
X534877Y-33945D01*
X535085Y-35030D01*
X535919Y-36425D01*
X530502Y-35960D01*
Y-31775D01*
G01X543002Y-21700D02*
X530502D01*
X533002Y-23560D01*
G01X543002D02*
Y-19840D01*
G01X543419Y-9300D02*
X543210Y-9610D01*
X542794D01*
X542585Y-9300D01*
X542794Y-8990D01*
X543210D01*
X543419Y-9300D01*
G01X541544Y465D02*
X542585Y1550D01*
X543002Y2790D01*
X542585Y4030D01*
X541336Y5115D01*
X539460Y5890D01*
X537585Y6200D01*
X535294D01*
X533419Y5890D01*
X531752Y5115D01*
X530919Y4185D01*
X530502Y3100D01*
X530919Y1860D01*
X531752Y930D01*
X533002Y310D01*
X534669Y0D01*
X536127Y310D01*
X537585Y1085D01*
X538419Y2015D01*
X538627Y3100D01*
X538211Y4340D01*
X537169Y5270D01*
X535294Y6200D01*
G01X603675Y-211865D02*
X848084D01*
Y-495880D01*
X603675D01*
Y-211865D01*
G01X650919Y-363290D02*
G03I-5906J0D01*
G01X650712Y-264787D02*
G03I-6250J0D01*
G01X659187Y-436518D02*
X668635D01*
G02Y-444392I0J-3937D01*
G01X659187D01*
G01X688320Y-436518D02*
G03Y-444392I0J-3937D01*
G01X697769D01*
G01X688320Y-436518D02*
X697769D01*
M02*
